G04 ================== begin FILE IDENTIFICATION RECORD ==================*
G04 Layout Name:  13948-1b.brd*
G04 Film Name:    BSMD*
G04 File Format:  Gerber RS274X*
G04 File Origin:  Cadence Allegro 16.5-S045*
G04 Origin Date:  Thu Nov 13 15:45:48 2014*
G04 *
G04 Layer:  VIA CLASS/PASTEMASK_BOTTOM*
G04 Layer:  PIN/PASTEMASK_BOTTOM*
G04 Layer:  PACKAGE GEOMETRY/PASTEMASK_BOTTOM*
G04 Layer:  DRAWING FORMAT/LAYER_PCB_STORY*
G04 Layer:  DRAWING FORMAT/LAYER_PAST_B*
G04 Layer:  BOARD GEOMETRY/PANEL_OUTLINE*
G04 *
G04 Offset:    (0.00 0.00)*
G04 Mirror:    No*
G04 Mode:      Positive*
G04 Rotation:  0*
G04 FullContactRelief:  No*
G04 UndefLineWidth:     6.00*
G04 ================== end FILE IDENTIFICATION RECORD ====================*
%FSLAX35Y35*MOIN*%
%IR0*IPPOS*OFA0.00000B0.00000*MIA0B0*SFA1.00000B1.00000*%
%AMMACRO15*
4,1,40,.011,.007,
.011,-.007,
.010939,-.007695,
.010759,-.008368,
.010464,-.009,
.010064,-.009571,
.009571,-.010064,
.009,-.010464,
.008368,-.010759,
.007695,-.010939,
.007,-.011,
-.007,-.011,
-.007695,-.010939,
-.008368,-.010759,
-.009,-.010464,
-.009571,-.010064,
-.010064,-.009571,
-.010464,-.009,
-.010759,-.008368,
-.010939,-.007695,
-.011,-.007,
-.011,.007,
-.010939,.007695,
-.010759,.008368,
-.010464,.009,
-.010064,.009571,
-.009571,.010064,
-.009,.010464,
-.008368,.010759,
-.007695,.010939,
-.007,.011,
.007,.011,
.007695,.010939,
.008368,.010759,
.009,.010464,
.009571,.010064,
.010064,.009571,
.010464,.009,
.010759,.008368,
.010939,.007695,
.011,.007,
0.0*
%
%ADD15MACRO15*%
%AMMACRO50*
4,1,40,.013,-.017,
-.013,-.017,
-.013695,-.016939,
-.014368,-.016759,
-.015,-.016464,
-.015571,-.016064,
-.016064,-.015571,
-.016464,-.015,
-.016759,-.014368,
-.016939,-.013695,
-.017,-.013,
-.017,.013,
-.016939,.013695,
-.016759,.014368,
-.016464,.015,
-.016064,.015571,
-.015571,.016064,
-.015,.016464,
-.014368,.016759,
-.013695,.016939,
-.013,.017,
.013,.017,
.013695,.016939,
.014368,.016759,
.015,.016464,
.015571,.016064,
.016064,.015571,
.016464,.015,
.016759,.014368,
.016939,.013695,
.017,.013,
.017,-.013,
.016939,-.013695,
.016759,-.014368,
.016464,-.015,
.016064,-.015571,
.015571,-.016064,
.015,-.016464,
.014368,-.016759,
.013695,-.016939,
.013,-.017,
0.0*
%
%ADD50MACRO50*%
%AMMACRO23*
4,1,40,-.017,-.013,
-.017,.013,
-.016939,.013695,
-.016759,.014368,
-.016464,.015,
-.016064,.015571,
-.015571,.016064,
-.015,.016464,
-.014368,.016759,
-.013695,.016939,
-.013,.017,
.013,.017,
.013695,.016939,
.014368,.016759,
.015,.016464,
.015571,.016064,
.016064,.015571,
.016464,.015,
.016759,.014368,
.016939,.013695,
.017,.013,
.017,-.013,
.016939,-.013695,
.016759,-.014368,
.016464,-.015,
.016064,-.015571,
.015571,-.016064,
.015,-.016464,
.014368,-.016759,
.013695,-.016939,
.013,-.017,
-.013,-.017,
-.013695,-.016939,
-.014368,-.016759,
-.015,-.016464,
-.015571,-.016064,
-.016064,-.015571,
-.016464,-.015,
-.016759,-.014368,
-.016939,-.013695,
-.017,-.013,
0.0*
%
%ADD23MACRO23*%
%AMMACRO52*
4,1,3,0.0,-.0125,
.025,.0125,
-.025,.0125,
0.0,-.0125,
0.0*
%
%ADD52MACRO52*%
%ADD16C,.04*%
%ADD21C,.032*%
%AMMACRO36*
4,1,40,-.007,-.004,
-.007,.004,
-.00697,.004347,
-.006879,.004684,
-.006732,.005,
-.006532,.005286,
-.006286,.005532,
-.006,.005732,
-.005684,.005879,
-.005347,.00597,
-.005,.006,
.005,.006,
.005347,.00597,
.005684,.005879,
.006,.005732,
.006286,.005532,
.006532,.005286,
.006732,.005,
.006879,.004684,
.00697,.004347,
.007,.004,
.007,-.004,
.00697,-.004347,
.006879,-.004684,
.006732,-.005,
.006532,-.005286,
.006286,-.005532,
.006,-.005732,
.005684,-.005879,
.005347,-.00597,
.005,-.006,
-.005,-.006,
-.005347,-.00597,
-.005684,-.005879,
-.006,-.005732,
-.006286,-.005532,
-.006532,-.005286,
-.006732,-.005,
-.006879,-.004684,
-.00697,-.004347,
-.007,-.004,
0.0*
%
%ADD36MACRO36*%
%AMMACRO39*
4,1,40,-.004,.007,
.004,.007,
.004347,.00697,
.004684,.006879,
.005,.006732,
.005286,.006532,
.005532,.006286,
.005732,.006,
.005879,.005684,
.00597,.005347,
.006,.005,
.006,-.005,
.00597,-.005347,
.005879,-.005684,
.005732,-.006,
.005532,-.006286,
.005286,-.006532,
.005,-.006732,
.004684,-.006879,
.004347,-.00697,
.004,-.007,
-.004,-.007,
-.004347,-.00697,
-.004684,-.006879,
-.005,-.006732,
-.005286,-.006532,
-.005532,-.006286,
-.005732,-.006,
-.005879,-.005684,
-.00597,-.005347,
-.006,-.005,
-.006,.005,
-.00597,.005347,
-.005879,.005684,
-.005732,.006,
-.005532,.006286,
-.005286,.006532,
-.005,.006732,
-.004684,.006879,
-.004347,.00697,
-.004,.007,
0.0*
%
%ADD39MACRO39*%
%ADD33C,.028*%
%ADD44R,.297X.081*%
%AMMACRO24*
4,1,40,.0225,.007,
.022378,.008389,
.022018,.009736,
.021428,.011,
.020628,.012142,
.019642,.013128,
.0185,.013928,
.017236,.014518,
.015889,.014878,
.0145,.015,
-.0145,.015,
-.015889,.014878,
-.017236,.014518,
-.0185,.013928,
-.019642,.013128,
-.020628,.012142,
-.021428,.011,
-.022018,.009736,
-.022378,.008389,
-.0225,.007,
-.0225,-.007,
-.022378,-.008389,
-.022018,-.009736,
-.021428,-.011,
-.020628,-.012142,
-.019642,-.013128,
-.0185,-.013928,
-.017236,-.014518,
-.015889,-.014878,
-.0145,-.015,
.0145,-.015,
.015889,-.014878,
.017236,-.014518,
.0185,-.013928,
.019642,-.013128,
.020628,-.012142,
.021428,-.011,
.022018,-.009736,
.022378,-.008389,
.0225,-.007,
.0225,.007,
0.0*
%
%ADD24MACRO24*%
%AMMACRO46*
4,1,40,.007,-.0225,
.008389,-.022378,
.009736,-.022018,
.011,-.021428,
.012142,-.020628,
.013128,-.019642,
.013928,-.0185,
.014518,-.017236,
.014878,-.015889,
.015,-.0145,
.015,.0145,
.014878,.015889,
.014518,.017236,
.013928,.0185,
.013128,.019642,
.012142,.020628,
.011,.021428,
.009736,.022018,
.008389,.022378,
.007,.0225,
-.007,.0225,
-.008389,.022378,
-.009736,.022018,
-.011,.021428,
-.012142,.020628,
-.013128,.019642,
-.013928,.0185,
-.014518,.017236,
-.014878,.015889,
-.015,.0145,
-.015,-.0145,
-.014878,-.015889,
-.014518,-.017236,
-.013928,-.0185,
-.013128,-.019642,
-.012142,-.020628,
-.011,-.021428,
-.009736,-.022018,
-.008389,-.022378,
-.007,-.0225,
.007,-.0225,
0.0*
%
%ADD46MACRO46*%
%AMMACRO30*
4,1,40,-.011,-.007,
-.011,.007,
-.010939,.007695,
-.010759,.008368,
-.010464,.009,
-.010064,.009571,
-.009571,.010064,
-.009,.010464,
-.008368,.010759,
-.007695,.010939,
-.007,.011,
.007,.011,
.007695,.010939,
.008368,.010759,
.009,.010464,
.009571,.010064,
.010064,.009571,
.010464,.009,
.010759,.008368,
.010939,.007695,
.011,.007,
.011,-.007,
.010939,-.007695,
.010759,-.008368,
.010464,-.009,
.010064,-.009571,
.009571,-.010064,
.009,-.010464,
.008368,-.010759,
.007695,-.010939,
.007,-.011,
-.007,-.011,
-.007695,-.010939,
-.008368,-.010759,
-.009,-.010464,
-.009571,-.010064,
-.010064,-.009571,
-.010464,-.009,
-.010759,-.008368,
-.010939,-.007695,
-.011,-.007,
0.0*
%
%ADD30MACRO30*%
%AMMACRO22*
4,1,40,.007,-.011,
-.007,-.011,
-.007695,-.010939,
-.008368,-.010759,
-.009,-.010464,
-.009571,-.010064,
-.010064,-.009571,
-.010464,-.009,
-.010759,-.008368,
-.010939,-.007695,
-.011,-.007,
-.011,.007,
-.010939,.007695,
-.010759,.008368,
-.010464,.009,
-.010064,.009571,
-.009571,.010064,
-.009,.010464,
-.008368,.010759,
-.007695,.010939,
-.007,.011,
.007,.011,
.007695,.010939,
.008368,.010759,
.009,.010464,
.009571,.010064,
.010064,.009571,
.010464,.009,
.010759,.008368,
.010939,.007695,
.011,.007,
.011,-.007,
.010939,-.007695,
.010759,-.008368,
.010464,-.009,
.010064,-.009571,
.009571,-.010064,
.009,-.010464,
.008368,-.010759,
.007695,-.010939,
.007,-.011,
0.0*
%
%ADD22MACRO22*%
%AMMACRO18*
4,1,40,-.012,-.008,
-.012,.008,
-.011939,.008695,
-.011759,.009368,
-.011464,.01,
-.011064,.010571,
-.010571,.011064,
-.01,.011464,
-.009368,.011759,
-.008695,.011939,
-.008,.012,
.008,.012,
.008695,.011939,
.009368,.011759,
.01,.011464,
.010571,.011064,
.011064,.010571,
.011464,.01,
.011759,.009368,
.011939,.008695,
.012,.008,
.012,-.008,
.011939,-.008695,
.011759,-.009368,
.011464,-.01,
.011064,-.010571,
.010571,-.011064,
.01,-.011464,
.009368,-.011759,
.008695,-.011939,
.008,-.012,
-.008,-.012,
-.008695,-.011939,
-.009368,-.011759,
-.01,-.011464,
-.010571,-.011064,
-.011064,-.010571,
-.011464,-.01,
-.011759,-.009368,
-.011939,-.008695,
-.012,-.008,
0.0*
%
%ADD18MACRO18*%
%AMMACRO11*
4,1,40,-.008,.012,
.008,.012,
.008695,.011939,
.009368,.011759,
.01,.011464,
.010571,.011064,
.011064,.010571,
.011464,.01,
.011759,.009368,
.011939,.008695,
.012,.008,
.012,-.008,
.011939,-.008695,
.011759,-.009368,
.011464,-.01,
.011064,-.010571,
.010571,-.011064,
.01,-.011464,
.009368,-.011759,
.008695,-.011939,
.008,-.012,
-.008,-.012,
-.008695,-.011939,
-.009368,-.011759,
-.01,-.011464,
-.010571,-.011064,
-.011064,-.010571,
-.011464,-.01,
-.011759,-.009368,
-.011939,-.008695,
-.012,-.008,
-.012,.008,
-.011939,.008695,
-.011759,.009368,
-.011464,.01,
-.011064,.010571,
-.010571,.011064,
-.01,.011464,
-.009368,.011759,
-.008695,.011939,
-.008,.012,
0.0*
%
%ADD11MACRO11*%
%AMMACRO47*
4,1,40,-.013,.017,
.013,.017,
.013695,.016939,
.014368,.016759,
.015,.016464,
.015571,.016064,
.016064,.015571,
.016464,.015,
.016759,.014368,
.016939,.013695,
.017,.013,
.017,-.013,
.016939,-.013695,
.016759,-.014368,
.016464,-.015,
.016064,-.015571,
.015571,-.016064,
.015,-.016464,
.014368,-.016759,
.013695,-.016939,
.013,-.017,
-.013,-.017,
-.013695,-.016939,
-.014368,-.016759,
-.015,-.016464,
-.015571,-.016064,
-.016064,-.015571,
-.016464,-.015,
-.016759,-.014368,
-.016939,-.013695,
-.017,-.013,
-.017,.013,
-.016939,.013695,
-.016759,.014368,
-.016464,.015,
-.016064,.015571,
-.015571,.016064,
-.015,.016464,
-.014368,.016759,
-.013695,.016939,
-.013,.017,
0.0*
%
%ADD47MACRO47*%
%AMMACRO37*
4,1,40,.017,.013,
.017,-.013,
.016939,-.013695,
.016759,-.014368,
.016464,-.015,
.016064,-.015571,
.015571,-.016064,
.015,-.016464,
.014368,-.016759,
.013695,-.016939,
.013,-.017,
-.013,-.017,
-.013695,-.016939,
-.014368,-.016759,
-.015,-.016464,
-.015571,-.016064,
-.016064,-.015571,
-.016464,-.015,
-.016759,-.014368,
-.016939,-.013695,
-.017,-.013,
-.017,.013,
-.016939,.013695,
-.016759,.014368,
-.016464,.015,
-.016064,.015571,
-.015571,.016064,
-.015,.016464,
-.014368,.016759,
-.013695,.016939,
-.013,.017,
.013,.017,
.013695,.016939,
.014368,.016759,
.015,.016464,
.015571,.016064,
.016064,.015571,
.016464,.015,
.016759,.014368,
.016939,.013695,
.017,.013,
0.0*
%
%ADD37MACRO37*%
%AMMACRO31*
4,1,40,-.011,-.007,
-.011,.007,
-.010939,.007695,
-.010759,.008368,
-.010464,.009,
-.010064,.009571,
-.009571,.010064,
-.009,.010464,
-.008368,.010759,
-.007695,.010939,
-.007,.011,
.007,.011,
.007695,.010939,
.008368,.010759,
.009,.010464,
.009571,.010064,
.010064,.009571,
.010464,.009,
.010759,.008368,
.010939,.007695,
.011,.007,
.011,-.007,
.010939,-.007695,
.010759,-.008368,
.010464,-.009,
.010064,-.009571,
.009571,-.010064,
.009,-.010464,
.008368,-.010759,
.007695,-.010939,
.007,-.011,
-.007,-.011,
-.007695,-.010939,
-.008368,-.010759,
-.009,-.010464,
-.009571,-.010064,
-.010064,-.009571,
-.010464,-.009,
-.010759,-.008368,
-.010939,-.007695,
-.011,-.007,
0.0*
%
%ADD31MACRO31*%
%AMMACRO26*
4,1,40,.007,-.011,
-.007,-.011,
-.007695,-.010939,
-.008368,-.010759,
-.009,-.010464,
-.009571,-.010064,
-.010064,-.009571,
-.010464,-.009,
-.010759,-.008368,
-.010939,-.007695,
-.011,-.007,
-.011,.007,
-.010939,.007695,
-.010759,.008368,
-.010464,.009,
-.010064,.009571,
-.009571,.010064,
-.009,.010464,
-.008368,.010759,
-.007695,.010939,
-.007,.011,
.007,.011,
.007695,.010939,
.008368,.010759,
.009,.010464,
.009571,.010064,
.010064,.009571,
.010464,.009,
.010759,.008368,
.010939,.007695,
.011,.007,
.011,-.007,
.010939,-.007695,
.010759,-.008368,
.010464,-.009,
.010064,-.009571,
.009571,-.010064,
.009,-.010464,
.008368,-.010759,
.007695,-.010939,
.007,-.011,
0.0*
%
%ADD26MACRO26*%
%AMMACRO17*
4,1,40,-.012,-.008,
-.012,.008,
-.011939,.008695,
-.011759,.009368,
-.011464,.01,
-.011064,.010571,
-.010571,.011064,
-.01,.011464,
-.009368,.011759,
-.008695,.011939,
-.008,.012,
.008,.012,
.008695,.011939,
.009368,.011759,
.01,.011464,
.010571,.011064,
.011064,.010571,
.011464,.01,
.011759,.009368,
.011939,.008695,
.012,.008,
.012,-.008,
.011939,-.008695,
.011759,-.009368,
.011464,-.01,
.011064,-.010571,
.010571,-.011064,
.01,-.011464,
.009368,-.011759,
.008695,-.011939,
.008,-.012,
-.008,-.012,
-.008695,-.011939,
-.009368,-.011759,
-.01,-.011464,
-.010571,-.011064,
-.011064,-.010571,
-.011464,-.01,
-.011759,-.009368,
-.011939,-.008695,
-.012,-.008,
0.0*
%
%ADD17MACRO17*%
%AMMACRO10*
4,1,40,-.008,.012,
.008,.012,
.008695,.011939,
.009368,.011759,
.01,.011464,
.010571,.011064,
.011064,.010571,
.011464,.01,
.011759,.009368,
.011939,.008695,
.012,.008,
.012,-.008,
.011939,-.008695,
.011759,-.009368,
.011464,-.01,
.011064,-.010571,
.010571,-.011064,
.01,-.011464,
.009368,-.011759,
.008695,-.011939,
.008,-.012,
-.008,-.012,
-.008695,-.011939,
-.009368,-.011759,
-.01,-.011464,
-.010571,-.011064,
-.011064,-.010571,
-.011464,-.01,
-.011759,-.009368,
-.011939,-.008695,
-.012,-.008,
-.012,.008,
-.011939,.008695,
-.011759,.009368,
-.011464,.01,
-.011064,.010571,
-.010571,.011064,
-.01,.011464,
-.009368,.011759,
-.008695,.011939,
-.008,.012,
0.0*
%
%ADD10MACRO10*%
%AMMACRO48*
4,1,40,-.013,.017,
.013,.017,
.013695,.016939,
.014368,.016759,
.015,.016464,
.015571,.016064,
.016064,.015571,
.016464,.015,
.016759,.014368,
.016939,.013695,
.017,.013,
.017,-.013,
.016939,-.013695,
.016759,-.014368,
.016464,-.015,
.016064,-.015571,
.015571,-.016064,
.015,-.016464,
.014368,-.016759,
.013695,-.016939,
.013,-.017,
-.013,-.017,
-.013695,-.016939,
-.014368,-.016759,
-.015,-.016464,
-.015571,-.016064,
-.016064,-.015571,
-.016464,-.015,
-.016759,-.014368,
-.016939,-.013695,
-.017,-.013,
-.017,.013,
-.016939,.013695,
-.016759,.014368,
-.016464,.015,
-.016064,.015571,
-.015571,.016064,
-.015,.016464,
-.014368,.016759,
-.013695,.016939,
-.013,.017,
0.0*
%
%ADD48MACRO48*%
%AMMACRO38*
4,1,40,.017,.013,
.017,-.013,
.016939,-.013695,
.016759,-.014368,
.016464,-.015,
.016064,-.015571,
.015571,-.016064,
.015,-.016464,
.014368,-.016759,
.013695,-.016939,
.013,-.017,
-.013,-.017,
-.013695,-.016939,
-.014368,-.016759,
-.015,-.016464,
-.015571,-.016064,
-.016064,-.015571,
-.016464,-.015,
-.016759,-.014368,
-.016939,-.013695,
-.017,-.013,
-.017,.013,
-.016939,.013695,
-.016759,.014368,
-.016464,.015,
-.016064,.015571,
-.015571,.016064,
-.015,.016464,
-.014368,.016759,
-.013695,.016939,
-.013,.017,
.013,.017,
.013695,.016939,
.014368,.016759,
.015,.016464,
.015571,.016064,
.016064,.015571,
.016464,.015,
.016759,.014368,
.016939,.013695,
.017,.013,
0.0*
%
%ADD38MACRO38*%
%AMMACRO53*
4,1,3,.025,-.0125,
0.0,.0125,
-.025,-.0125,
.025,-.0125,
0.0*
%
%ADD53MACRO53*%
%ADD51R,.02X.06*%
%ADD43R,.012X.038*%
%ADD42R,.038X.012*%
%AMMACRO40*
4,1,40,.004,-.007,
-.004,-.007,
-.004347,-.00697,
-.004684,-.006879,
-.005,-.006732,
-.005286,-.006532,
-.005532,-.006286,
-.005732,-.006,
-.005879,-.005684,
-.00597,-.005347,
-.006,-.005,
-.006,.005,
-.00597,.005347,
-.005879,.005684,
-.005732,.006,
-.005532,.006286,
-.005286,.006532,
-.005,.006732,
-.004684,.006879,
-.004347,.00697,
-.004,.007,
.004,.007,
.004347,.00697,
.004684,.006879,
.005,.006732,
.005286,.006532,
.005532,.006286,
.005732,.006,
.005879,.005684,
.00597,.005347,
.006,.005,
.006,-.005,
.00597,-.005347,
.005879,-.005684,
.005732,-.006,
.005532,-.006286,
.005286,-.006532,
.005,-.006732,
.004684,-.006879,
.004347,-.00697,
.004,-.007,
0.0*
%
%ADD40MACRO40*%
%AMMACRO27*
4,1,40,.007,.004,
.007,-.004,
.00697,-.004347,
.006879,-.004684,
.006732,-.005,
.006532,-.005286,
.006286,-.005532,
.006,-.005732,
.005684,-.005879,
.005347,-.00597,
.005,-.006,
-.005,-.006,
-.005347,-.00597,
-.005684,-.005879,
-.006,-.005732,
-.006286,-.005532,
-.006532,-.005286,
-.006732,-.005,
-.006879,-.004684,
-.00697,-.004347,
-.007,-.004,
-.007,.004,
-.00697,.004347,
-.006879,.004684,
-.006732,.005,
-.006532,.005286,
-.006286,.005532,
-.006,.005732,
-.005684,.005879,
-.005347,.00597,
-.005,.006,
.005,.006,
.005347,.00597,
.005684,.005879,
.006,.005732,
.006286,.005532,
.006532,.005286,
.006732,.005,
.006879,.004684,
.00697,.004347,
.007,.004,
0.0*
%
%ADD27MACRO27*%
%ADD28R,.045X.055*%
%ADD32R,.016X.048*%
%ADD29R,.055X.045*%
%AMMACRO45*
4,1,40,-.007,.0225,
-.008389,.022378,
-.009736,.022018,
-.011,.021428,
-.012142,.020628,
-.013128,.019642,
-.013928,.0185,
-.014518,.017236,
-.014878,.015889,
-.015,.0145,
-.015,-.0145,
-.014878,-.015889,
-.014518,-.017236,
-.013928,-.0185,
-.013128,-.019642,
-.012142,-.020628,
-.011,-.021428,
-.009736,-.022018,
-.008389,-.022378,
-.007,-.0225,
.007,-.0225,
.008389,-.022378,
.009736,-.022018,
.011,-.021428,
.012142,-.020628,
.013128,-.019642,
.013928,-.0185,
.014518,-.017236,
.014878,-.015889,
.015,-.0145,
.015,.0145,
.014878,.015889,
.014518,.017236,
.013928,.0185,
.013128,.019642,
.012142,.020628,
.011,.021428,
.009736,.022018,
.008389,.022378,
.007,.0225,
-.007,.0225,
0.0*
%
%ADD45MACRO45*%
%AMMACRO41*
4,1,40,.024,-.012,
.024,.012,
.023878,.013389,
.023518,.014736,
.022928,.016,
.022128,.017142,
.021142,.018128,
.02,.018928,
.018736,.019518,
.017389,.019878,
.016,.02,
-.016,.02,
-.017389,.019878,
-.018736,.019518,
-.02,.018928,
-.021142,.018128,
-.022128,.017142,
-.022928,.016,
-.023518,.014736,
-.023878,.013389,
-.024,.012,
-.024,-.012,
-.023878,-.013389,
-.023518,-.014736,
-.022928,-.016,
-.022128,-.017142,
-.021142,-.018128,
-.02,-.018928,
-.018736,-.019518,
-.017389,-.019878,
-.016,-.02,
.016,-.02,
.017389,-.019878,
.018736,-.019518,
.02,-.018928,
.021142,-.018128,
.022128,-.017142,
.022928,-.016,
.023518,-.014736,
.023878,-.013389,
.024,-.012,
0.0*
%
%ADD41MACRO41*%
%AMMACRO35*
4,1,40,.008,-.012,
-.008,-.012,
-.008695,-.011939,
-.009368,-.011759,
-.01,-.011464,
-.010571,-.011064,
-.011064,-.010571,
-.011464,-.01,
-.011759,-.009368,
-.011939,-.008695,
-.012,-.008,
-.012,.008,
-.011939,.008695,
-.011759,.009368,
-.011464,.01,
-.011064,.010571,
-.010571,.011064,
-.01,.011464,
-.009368,.011759,
-.008695,.011939,
-.008,.012,
.008,.012,
.008695,.011939,
.009368,.011759,
.01,.011464,
.010571,.011064,
.011064,.010571,
.011464,.01,
.011759,.009368,
.011939,.008695,
.012,.008,
.012,-.008,
.011939,-.008695,
.011759,-.009368,
.011464,-.01,
.011064,-.010571,
.010571,-.011064,
.01,-.011464,
.009368,-.011759,
.008695,-.011939,
.008,-.012,
0.0*
%
%ADD35MACRO35*%
%AMMACRO19*
4,1,40,.012,.008,
.012,-.008,
.011939,-.008695,
.011759,-.009368,
.011464,-.01,
.011064,-.010571,
.010571,-.011064,
.01,-.011464,
.009368,-.011759,
.008695,-.011939,
.008,-.012,
-.008,-.012,
-.008695,-.011939,
-.009368,-.011759,
-.01,-.011464,
-.010571,-.011064,
-.011064,-.010571,
-.011464,-.01,
-.011759,-.009368,
-.011939,-.008695,
-.012,-.008,
-.012,.008,
-.011939,.008695,
-.011759,.009368,
-.011464,.01,
-.011064,.010571,
-.010571,.011064,
-.01,.011464,
-.009368,.011759,
-.008695,.011939,
-.008,.012,
.008,.012,
.008695,.011939,
.009368,.011759,
.01,.011464,
.010571,.011064,
.011064,.010571,
.011464,.01,
.011759,.009368,
.011939,.008695,
.012,.008,
0.0*
%
%ADD19MACRO19*%
%AMMACRO12*
4,1,40,-.007,.011,
.007,.011,
.007695,.010939,
.008368,.010759,
.009,.010464,
.009571,.010064,
.010064,.009571,
.010464,.009,
.010759,.008368,
.010939,.007695,
.011,.007,
.011,-.007,
.010939,-.007695,
.010759,-.008368,
.010464,-.009,
.010064,-.009571,
.009571,-.010064,
.009,-.010464,
.008368,-.010759,
.007695,-.010939,
.007,-.011,
-.007,-.011,
-.007695,-.010939,
-.008368,-.010759,
-.009,-.010464,
-.009571,-.010064,
-.010064,-.009571,
-.010464,-.009,
-.010759,-.008368,
-.010939,-.007695,
-.011,-.007,
-.011,.007,
-.010939,.007695,
-.010759,.008368,
-.010464,.009,
-.010064,.009571,
-.009571,.010064,
-.009,.010464,
-.008368,.010759,
-.007695,.010939,
-.007,.011,
0.0*
%
%ADD12MACRO12*%
%AMMACRO14*
4,1,40,.011,.007,
.011,-.007,
.010939,-.007695,
.010759,-.008368,
.010464,-.009,
.010064,-.009571,
.009571,-.010064,
.009,-.010464,
.008368,-.010759,
.007695,-.010939,
.007,-.011,
-.007,-.011,
-.007695,-.010939,
-.008368,-.010759,
-.009,-.010464,
-.009571,-.010064,
-.010064,-.009571,
-.010464,-.009,
-.010759,-.008368,
-.010939,-.007695,
-.011,-.007,
-.011,.007,
-.010939,.007695,
-.010759,.008368,
-.010464,.009,
-.010064,.009571,
-.009571,.010064,
-.009,.010464,
-.008368,.010759,
-.007695,.010939,
-.007,.011,
.007,.011,
.007695,.010939,
.008368,.010759,
.009,.010464,
.009571,.010064,
.010064,.009571,
.010464,.009,
.010759,.008368,
.010939,.007695,
.011,.007,
0.0*
%
%ADD14MACRO14*%
%AMMACRO49*
4,1,40,.013,-.017,
-.013,-.017,
-.013695,-.016939,
-.014368,-.016759,
-.015,-.016464,
-.015571,-.016064,
-.016064,-.015571,
-.016464,-.015,
-.016759,-.014368,
-.016939,-.013695,
-.017,-.013,
-.017,.013,
-.016939,.013695,
-.016759,.014368,
-.016464,.015,
-.016064,.015571,
-.015571,.016064,
-.015,.016464,
-.014368,.016759,
-.013695,.016939,
-.013,.017,
.013,.017,
.013695,.016939,
.014368,.016759,
.015,.016464,
.015571,.016064,
.016064,.015571,
.016464,.015,
.016759,.014368,
.016939,.013695,
.017,.013,
.017,-.013,
.016939,-.013695,
.016759,-.014368,
.016464,-.015,
.016064,-.015571,
.015571,-.016064,
.015,-.016464,
.014368,-.016759,
.013695,-.016939,
.013,-.017,
0.0*
%
%ADD49MACRO49*%
%AMMACRO25*
4,1,40,-.017,-.013,
-.017,.013,
-.016939,.013695,
-.016759,.014368,
-.016464,.015,
-.016064,.015571,
-.015571,.016064,
-.015,.016464,
-.014368,.016759,
-.013695,.016939,
-.013,.017,
.013,.017,
.013695,.016939,
.014368,.016759,
.015,.016464,
.015571,.016064,
.016064,.015571,
.016464,.015,
.016759,.014368,
.016939,.013695,
.017,.013,
.017,-.013,
.016939,-.013695,
.016759,-.014368,
.016464,-.015,
.016064,-.015571,
.015571,-.016064,
.015,-.016464,
.014368,-.016759,
.013695,-.016939,
.013,-.017,
-.013,-.017,
-.013695,-.016939,
-.014368,-.016759,
-.015,-.016464,
-.015571,-.016064,
-.016064,-.015571,
-.016464,-.015,
-.016759,-.014368,
-.016939,-.013695,
-.017,-.013,
0.0*
%
%ADD25MACRO25*%
%AMMACRO34*
4,1,40,.008,-.012,
-.008,-.012,
-.008695,-.011939,
-.009368,-.011759,
-.01,-.011464,
-.010571,-.011064,
-.011064,-.010571,
-.011464,-.01,
-.011759,-.009368,
-.011939,-.008695,
-.012,-.008,
-.012,.008,
-.011939,.008695,
-.011759,.009368,
-.011464,.01,
-.011064,.010571,
-.010571,.011064,
-.01,.011464,
-.009368,.011759,
-.008695,.011939,
-.008,.012,
.008,.012,
.008695,.011939,
.009368,.011759,
.01,.011464,
.010571,.011064,
.011064,.010571,
.011464,.01,
.011759,.009368,
.011939,.008695,
.012,.008,
.012,-.008,
.011939,-.008695,
.011759,-.009368,
.011464,-.01,
.011064,-.010571,
.010571,-.011064,
.01,-.011464,
.009368,-.011759,
.008695,-.011939,
.008,-.012,
0.0*
%
%ADD34MACRO34*%
%AMMACRO20*
4,1,40,.012,.008,
.012,-.008,
.011939,-.008695,
.011759,-.009368,
.011464,-.01,
.011064,-.010571,
.010571,-.011064,
.01,-.011464,
.009368,-.011759,
.008695,-.011939,
.008,-.012,
-.008,-.012,
-.008695,-.011939,
-.009368,-.011759,
-.01,-.011464,
-.010571,-.011064,
-.011064,-.010571,
-.011464,-.01,
-.011759,-.009368,
-.011939,-.008695,
-.012,-.008,
-.012,.008,
-.011939,.008695,
-.011759,.009368,
-.011464,.01,
-.011064,.010571,
-.010571,.011064,
-.01,.011464,
-.009368,.011759,
-.008695,.011939,
-.008,.012,
.008,.012,
.008695,.011939,
.009368,.011759,
.01,.011464,
.010571,.011064,
.011064,.010571,
.011464,.01,
.011759,.009368,
.011939,.008695,
.012,.008,
0.0*
%
%ADD20MACRO20*%
%AMMACRO13*
4,1,40,-.007,.011,
.007,.011,
.007695,.010939,
.008368,.010759,
.009,.010464,
.009571,.010064,
.010064,.009571,
.010464,.009,
.010759,.008368,
.010939,.007695,
.011,.007,
.011,-.007,
.010939,-.007695,
.010759,-.008368,
.010464,-.009,
.010064,-.009571,
.009571,-.010064,
.009,-.010464,
.008368,-.010759,
.007695,-.010939,
.007,-.011,
-.007,-.011,
-.007695,-.010939,
-.008368,-.010759,
-.009,-.010464,
-.009571,-.010064,
-.010064,-.009571,
-.010464,-.009,
-.010759,-.008368,
-.010939,-.007695,
-.011,-.007,
-.011,.007,
-.010939,.007695,
-.010759,.008368,
-.010464,.009,
-.010064,.009571,
-.009571,.010064,
-.009,.010464,
-.008368,.010759,
-.007695,.010939,
-.007,.011,
0.0*
%
%ADD13MACRO13*%
%ADD54C,.02*%
%ADD55C,.006*%
G75*
%LPD*%
G75*
G54D10*
X47476Y397079D03*
X43976D03*
X62976D03*
X56976D03*
X66476D03*
X53476D03*
X75476D03*
X71976D03*
X165795Y307509D03*
X179295D03*
X175295D03*
X169795D03*
X213795Y304009D03*
X209795D03*
X203795D03*
X200295D03*
X269678Y965800D03*
X273678D03*
X334000Y84300D03*
X346000Y116340D03*
X349000Y15300D03*
X361500D03*
X358000D03*
X360819Y210840D03*
X371239Y191970D03*
X371299Y199540D03*
X376929Y208800D03*
X386300Y164800D03*
X409429Y160800D03*
X399429D03*
X402929D03*
X422200Y160600D03*
X418714Y160650D03*
X415314D03*
X450678Y812300D03*
X507055Y412300D03*
X733716Y135584D03*
X730216D03*
X1006500Y78300D03*
X1277000Y701800D03*
X1273000Y719800D03*
G54D20*
X87388Y853252D03*
X123104Y796720D03*
Y800720D03*
X390729Y170500D03*
Y174000D03*
X390300Y197200D03*
Y200600D03*
X390800Y190000D03*
X401229Y170500D03*
X401329Y165000D03*
X401229Y177000D03*
Y183500D03*
Y190000D03*
X399359Y215180D03*
X409855Y338850D03*
X410755Y372000D03*
X415840Y139000D03*
X428529Y205200D03*
X428469Y208670D03*
X423539Y214650D03*
X415929Y214680D03*
X425355Y372500D03*
X427078Y824500D03*
X426978Y864000D03*
X438629Y151710D03*
X437679Y158620D03*
X437729Y170860D03*
X437819Y164850D03*
X437729Y177400D03*
X437929Y183800D03*
X438049Y202480D03*
X437729Y189750D03*
X438229Y196000D03*
X438039Y208870D03*
X459855Y326500D03*
X1010300Y70500D03*
X1063800Y120500D03*
X1163300Y704500D03*
X1170300Y685500D03*
X1170268Y695284D03*
Y689284D03*
X1179800Y701300D03*
X1170268Y700284D03*
X1358300Y456000D03*
G54D11*
X47476Y393479D03*
X43976D03*
X62976D03*
X56976D03*
X66476D03*
X53476D03*
X75476D03*
X71976D03*
X165795Y303909D03*
X179295D03*
X175295D03*
X169795D03*
X213795Y300409D03*
X209795D03*
X203795D03*
X200295D03*
X269678Y962200D03*
X273678D03*
X334000Y80700D03*
X346000Y112740D03*
X349000Y11700D03*
X361500D03*
X358000D03*
X360819Y207240D03*
X371239Y188370D03*
X371299Y195940D03*
X376929Y205200D03*
X386300Y161200D03*
X409429Y157200D03*
X399429D03*
X402929D03*
X422200Y157000D03*
X418714Y157050D03*
X415314D03*
X450678Y808700D03*
X507055Y408700D03*
X733716Y131984D03*
X730216D03*
X1006500Y74700D03*
X1277000Y698200D03*
X1273000Y716200D03*
G54D12*
X48700Y872500D03*
Y868500D03*
X340740Y193000D03*
X340629Y189000D03*
X340740Y197500D03*
X346700Y396000D03*
X362210Y179910D03*
X416700Y225000D03*
X441129Y113500D03*
X451629Y175500D03*
X470855Y308700D03*
X479700Y186231D03*
X479723Y334283D03*
X491478Y844000D03*
Y836000D03*
Y840000D03*
Y848500D03*
X527629Y124500D03*
X534700Y148500D03*
X780200Y973000D03*
X1039200Y141000D03*
X1081200Y667500D03*
Y679500D03*
Y675500D03*
Y671500D03*
Y683500D03*
X1069568Y681554D03*
X1081200Y695500D03*
Y687500D03*
Y691500D03*
Y699500D03*
Y711500D03*
Y707500D03*
Y703500D03*
Y723500D03*
Y719500D03*
Y715500D03*
Y727500D03*
X1082200Y736500D03*
X1089700Y630000D03*
X1091200Y655000D03*
X1091188Y650584D03*
X1171900Y679300D03*
X1225700Y727000D03*
Y718500D03*
Y735500D03*
Y731000D03*
X1261200Y651000D03*
Y657000D03*
Y661000D03*
X1253700Y671000D03*
X1261200Y667500D03*
X1253700Y687500D03*
Y683500D03*
G54D30*
X312000Y292700D03*
X321500Y85200D03*
X326000D03*
X317000D03*
X329500Y294200D03*
X341000Y116240D03*
X353500Y15200D03*
X393929Y224700D03*
X394555Y434700D03*
X402929Y233700D03*
X406929D03*
X399555Y434700D03*
X425940Y155000D03*
X413429Y240200D03*
X426523Y326983D03*
X425278Y808700D03*
X435055Y287700D03*
X430523Y326983D03*
X431778Y808700D03*
X437778Y879200D03*
X431278D03*
X456278Y808700D03*
X460778Y879200D03*
X462778Y808700D03*
X467278Y879200D03*
X509555Y420200D03*
X552555Y345200D03*
X556555D03*
X651000Y452200D03*
X645500Y475700D03*
X1137500Y656200D03*
X1166000Y648200D03*
X1153000D03*
X1158000D03*
X1162000D03*
X1213000Y634200D03*
X1209000D03*
X1217000D03*
X1260500Y641200D03*
X1277000Y690700D03*
X1273000Y709200D03*
X1281000Y719700D03*
X1277000Y727700D03*
X1358584Y284368D03*
X1384500Y322700D03*
G54D21*
X195295Y301709D03*
X188295Y301209D03*
X195295Y307709D03*
X188295Y315209D03*
X184295Y305709D03*
X195795Y313709D03*
X189795Y308709D03*
X183795Y311709D03*
X483178Y861500D03*
G54D13*
X45300Y872500D03*
Y868500D03*
X337340Y193000D03*
X337229Y189000D03*
X337340Y197500D03*
X343300Y396000D03*
X358810Y179910D03*
X413300Y225000D03*
X437729Y113500D03*
X448229Y175500D03*
X476300Y186231D03*
X467455Y308700D03*
X476323Y334283D03*
X488078Y844000D03*
Y836000D03*
Y840000D03*
Y848500D03*
X524229Y124500D03*
X531300Y148500D03*
X776800Y973000D03*
X1035800Y141000D03*
X1066168Y681554D03*
X1077800Y667500D03*
Y679500D03*
Y675500D03*
Y671500D03*
Y683500D03*
Y695500D03*
Y687500D03*
Y691500D03*
Y699500D03*
Y711500D03*
Y707500D03*
Y703500D03*
Y723500D03*
Y719500D03*
Y715500D03*
Y727500D03*
X1078800Y736500D03*
X1086300Y630000D03*
X1087800Y655000D03*
X1087788Y650584D03*
X1168500Y679300D03*
X1222300Y727000D03*
Y718500D03*
Y735500D03*
Y731000D03*
X1257800Y651000D03*
Y657000D03*
Y661000D03*
X1250300Y671000D03*
X1257800Y667500D03*
X1250300Y687500D03*
Y683500D03*
G54D40*
X375040Y147400D03*
Y149600D03*
X374629Y171100D03*
Y173300D03*
X389540Y130400D03*
Y132600D03*
X387029Y152600D03*
Y154800D03*
X380769Y152240D03*
Y154440D03*
X409040Y143900D03*
Y146100D03*
X399055Y441400D03*
Y443600D03*
X413929Y131400D03*
Y133600D03*
X453555Y362600D03*
Y364800D03*
X453455Y398100D03*
Y400300D03*
X451255Y398100D03*
Y400300D03*
X475855Y352700D03*
Y354900D03*
X474555Y417900D03*
X469055Y415900D03*
Y418100D03*
X474555Y420100D03*
X479055Y352900D03*
Y355100D03*
X482555Y378400D03*
Y380600D03*
X483055Y393900D03*
Y396100D03*
X481055Y405900D03*
Y408100D03*
X782324Y342948D03*
Y345148D03*
X778824Y342948D03*
Y345148D03*
G54D31*
X312000Y289300D03*
X321500Y81800D03*
X326000D03*
X317000D03*
X329500Y290800D03*
X341000Y112840D03*
X353500Y11800D03*
X393929Y221300D03*
X394555Y431300D03*
X402929Y230300D03*
X406929D03*
X399555Y431300D03*
X425940Y151600D03*
X413429Y236800D03*
X426523Y323583D03*
X425278Y805300D03*
X435055Y284300D03*
X430523Y323583D03*
X431778Y805300D03*
X437778Y875800D03*
X431278D03*
X456278Y805300D03*
X460778Y875800D03*
X462778Y805300D03*
X467278Y875800D03*
X509555Y416800D03*
X552555Y341800D03*
X556555D03*
X651000Y448800D03*
X645500Y472300D03*
X1137500Y652800D03*
X1166000Y644800D03*
X1153000D03*
X1158000D03*
X1162000D03*
X1213000Y630800D03*
X1209000D03*
X1217000D03*
X1260500Y637800D03*
X1277000Y687300D03*
X1273000Y705800D03*
X1281000Y716300D03*
X1277000Y724300D03*
X1358584Y280968D03*
X1384500Y319300D03*
G54D22*
X297800Y98500D03*
X305800D03*
X346380Y179800D03*
X361729Y199389D03*
X379800Y901500D03*
Y906000D03*
X403800Y889500D03*
Y893500D03*
Y905500D03*
Y897500D03*
Y909500D03*
Y901500D03*
X426800Y241000D03*
Y245000D03*
X425300Y314500D03*
X414823Y326283D03*
X423578Y828500D03*
Y837500D03*
Y842000D03*
Y833000D03*
Y846500D03*
Y851000D03*
Y860000D03*
Y855500D03*
X443340Y118000D03*
X433683Y145701D03*
X446229Y113500D03*
X448229Y171500D03*
Y184500D03*
Y180000D03*
X464729Y104000D03*
X467729Y122000D03*
X474300Y140000D03*
X470729Y149000D03*
Y153500D03*
X470800Y144500D03*
X471300Y157500D03*
X470800Y162000D03*
X466300Y169000D03*
Y176000D03*
X476331Y190291D03*
X462300Y286500D03*
X488078Y857000D03*
Y852500D03*
Y861500D03*
X508229Y135000D03*
X511229Y151000D03*
X524229Y129000D03*
X776800Y968500D03*
X1006800Y66500D03*
X1035800Y145500D03*
X1060300Y124500D03*
X1085300Y640000D03*
X1077800D03*
X1132138Y688864D03*
X1222300Y722500D03*
X1248300Y715500D03*
Y719500D03*
X1250300Y641000D03*
Y647000D03*
X1257800D03*
X1250300Y657000D03*
Y651000D03*
Y661000D03*
Y667000D03*
Y675500D03*
Y679500D03*
Y691500D03*
Y695500D03*
Y699500D03*
Y703500D03*
Y707500D03*
Y711500D03*
X1255800Y715500D03*
X1340800Y399500D03*
G54D14*
X43520Y910988D03*
X48020D03*
X52520D03*
X57020D03*
X61520D03*
X66020D03*
X99804Y913020D03*
X103804D03*
X107804D03*
X111804D03*
X115804D03*
X119804D03*
X123804D03*
X127804D03*
X131804D03*
X135804D03*
X313000Y89300D03*
X330000Y84300D03*
X314453Y245152D03*
X344040Y207300D03*
X357040D03*
X348540D03*
X353040D03*
X351000Y392800D03*
X373200Y179840D03*
X371429Y203800D03*
X380829Y187900D03*
X393000Y940800D03*
X406555Y323300D03*
X405000Y940800D03*
X409000D03*
X397000D03*
X401000D03*
X425278Y808800D03*
X413000Y940800D03*
X417000D03*
X429940Y151600D03*
X444055Y295300D03*
X431778Y808800D03*
X431278Y872300D03*
X437778D03*
X456278Y808800D03*
X460778Y872300D03*
X462778Y808800D03*
X467278Y872300D03*
X544178Y964800D03*
X548555Y341800D03*
X554955Y368200D03*
X558955D03*
X641000Y472300D03*
X646500Y448800D03*
X678500Y406800D03*
X787000Y411300D03*
X1010500Y74800D03*
X1178500Y644300D03*
X1281000Y687300D03*
Y705800D03*
X1273000Y698300D03*
X1281000D03*
X1277000Y716300D03*
X1281000Y724300D03*
X1292500Y413300D03*
X1372300Y281000D03*
X1384300D03*
G54D41*
X439029Y100000D03*
Y108000D03*
X447829Y104000D03*
X494329Y149500D03*
X485529Y145500D03*
Y153500D03*
G54D32*
X323060Y285250D03*
X317940D03*
Y291750D03*
X320500D03*
X323060D03*
G54D23*
X314500Y71200D03*
X307500Y288700D03*
X319500Y71200D03*
X332500Y68700D03*
X1031500Y63700D03*
X1036500D03*
X1041500D03*
X1046500D03*
X1051500D03*
X1124800Y804200D03*
X1131300D03*
X1142000Y799700D03*
X1212500Y197700D03*
X1204390Y703400D03*
G54D50*
X678800Y466000D03*
X1347317Y533012D03*
Y525012D03*
G54D42*
X437478Y845016D03*
Y843047D03*
Y848953D03*
Y846984D03*
X473078Y843047D03*
Y845016D03*
Y846984D03*
Y848953D03*
G54D51*
X1015740Y50500D03*
X1012000D03*
X1008260D03*
Y59500D03*
X1015740D03*
G54D24*
X299750Y88000D03*
X307250Y84125D03*
Y91875D03*
X343250Y287625D03*
X335750Y291500D03*
X343250Y295375D03*
X510179Y125500D03*
X517679Y121625D03*
Y129375D03*
G54D33*
X346129Y188200D03*
X345540Y202000D03*
X347040Y193000D03*
X358080Y184300D03*
X354410Y176460D03*
X350040Y184500D03*
Y198500D03*
X353040Y202500D03*
X357540Y199500D03*
X358440Y189300D03*
X361646Y990784D03*
X376140Y186800D03*
X375040Y197500D03*
X366678Y990500D03*
X386500Y362100D03*
X392900Y388000D03*
X380555Y407000D03*
X394555Y426000D03*
X412929Y145500D03*
X408429Y219700D03*
X401929Y225300D03*
X405555Y379000D03*
X401055Y381500D03*
X404555Y412000D03*
X399555Y426000D03*
X421540Y123500D03*
Y118500D03*
X428040Y123500D03*
X418040Y132500D03*
X425229Y128700D03*
X422940Y133000D03*
X428040D03*
X423329Y145620D03*
X417729Y145500D03*
X420219Y151810D03*
X426429Y196000D03*
X425126Y221124D03*
X425532Y228137D03*
X424000Y377000D03*
X433040Y119000D03*
X438540D03*
X444540Y122500D03*
X443042Y139065D03*
X433040Y132500D03*
X430040Y128500D03*
X438540Y132500D03*
X435040Y128000D03*
X445059Y127830D03*
X443429Y132400D03*
X442099Y187600D03*
X440009Y225589D03*
X431321Y232880D03*
X435659Y223364D03*
X442555Y324000D03*
X432555Y333500D03*
X436055Y342000D03*
X436555Y337000D03*
X432000Y366000D03*
X448229Y133000D03*
X452159Y125370D03*
X452929Y134500D03*
X458349Y137762D03*
X459929Y128500D03*
X454929Y130000D03*
X447349Y149920D03*
X450989Y153950D03*
X458839Y147900D03*
X450255Y140258D03*
X449429Y145500D03*
X454479Y150150D03*
X456929Y143000D03*
X455229Y162460D03*
X456309Y157740D03*
X451669Y159120D03*
X447129Y157000D03*
X447489Y162190D03*
X448876Y195275D03*
X450237Y200375D03*
X448055Y311500D03*
X452555Y316500D03*
X447055Y321500D03*
X456055D03*
X452555Y352900D03*
X448555Y338000D03*
X463429Y139000D03*
X465429Y127000D03*
X468600Y136700D03*
X462539Y144270D03*
X462500Y154000D03*
X468555Y323000D03*
X463055Y322500D03*
X472055Y334000D03*
X467255Y342600D03*
X472055Y341500D03*
X462555Y346000D03*
X556500Y184500D03*
X568500Y180500D03*
X566900Y195900D03*
X1127610Y663660D03*
X1133000Y657000D03*
X1127800Y656204D03*
X1121760Y665640D03*
X1143500Y655500D03*
Y660500D03*
X1138760Y671560D03*
X1141790Y667130D03*
X1139000Y678600D03*
X1145400Y673100D03*
X1142900Y705300D03*
X1164000Y655000D03*
Y660000D03*
X1167280Y672050D03*
X1158780Y670430D03*
X1168000Y706000D03*
X1163700Y714400D03*
X1175500Y660000D03*
X1171080Y675530D03*
X1173500Y683000D03*
X1170000Y710790D03*
X1173600Y704500D03*
X1184500Y730500D03*
X1180210Y718150D03*
X1187230Y702250D03*
X1193960Y713250D03*
X1194000Y703000D03*
X1190760Y719450D03*
X1196100Y719100D03*
X1184850Y720120D03*
X1187330Y715720D03*
G54D15*
X43520Y914388D03*
X48020D03*
X52520D03*
X57020D03*
X61520D03*
X66020D03*
X99804Y916420D03*
X103804D03*
X107804D03*
X111804D03*
X115804D03*
X119804D03*
X123804D03*
X127804D03*
X131804D03*
X135804D03*
X313000Y92700D03*
X330000Y87700D03*
X314453Y248552D03*
X344040Y210700D03*
X357040D03*
X348540D03*
X353040D03*
X351000Y396200D03*
X373200Y183240D03*
X371429Y207200D03*
X380829Y191300D03*
X393000Y944200D03*
X406555Y326700D03*
X405000Y944200D03*
X409000D03*
X397000D03*
X401000D03*
X425278Y812200D03*
X413000Y944200D03*
X417000D03*
X429940Y155000D03*
X444055Y298700D03*
X431778Y812200D03*
X431278Y875700D03*
X437778D03*
X456278Y812200D03*
X460778Y875700D03*
X462778Y812200D03*
X467278Y875700D03*
X544178Y968200D03*
X548555Y345200D03*
X554955Y371600D03*
X558955D03*
X641000Y475700D03*
X646500Y452200D03*
X678500Y410200D03*
X787000Y414700D03*
X1010500Y78200D03*
X1178500Y647700D03*
X1281000Y690700D03*
Y709200D03*
X1273000Y701700D03*
X1281000D03*
X1277000Y719700D03*
X1281000Y727700D03*
X1292500Y416700D03*
X1372300Y284400D03*
X1384300D03*
G54D34*
X343929Y215450D03*
X356929Y215700D03*
X364909Y190119D03*
X365429Y215450D03*
X394029Y196100D03*
X385429Y219700D03*
X410729Y196200D03*
X407214Y196250D03*
X403109Y215980D03*
X438055Y319200D03*
X461929Y180200D03*
X451055Y378200D03*
Y385700D03*
X455778Y872200D03*
X471429Y126200D03*
X489555Y427700D03*
X678400Y398800D03*
X731716Y109484D03*
X735216D03*
X1149268Y675884D03*
X1144768Y677484D03*
X1157000Y677200D03*
X1154300Y802700D03*
X1160300Y801200D03*
X1165300D03*
X1170300D03*
X1200370Y704450D03*
X1217000Y198700D03*
X1220500D03*
X1273236Y687078D03*
X1277000Y705700D03*
X1273000Y724200D03*
X1292500Y405700D03*
X1312500Y607700D03*
X1306500Y645200D03*
X1379500Y319200D03*
G54D25*
X314500Y76800D03*
X307500Y294300D03*
X319500Y76800D03*
X332500Y74300D03*
X1031500Y69300D03*
X1036500D03*
X1041500D03*
X1046500D03*
X1051500D03*
X1124800Y809800D03*
X1131300D03*
X1142000Y805300D03*
X1212500Y203300D03*
X1204390Y709000D03*
G54D43*
X439530Y839000D03*
X441498D03*
X443467D03*
Y853000D03*
X441498D03*
X439530D03*
X445435Y839000D03*
X447404D03*
X449372D03*
X451341D03*
X453309D03*
X455278D03*
X457247D03*
X459215D03*
X461184D03*
Y853000D03*
X459215D03*
X457247D03*
X455278D03*
X453309D03*
X451341D03*
X449372D03*
X447404D03*
X445435D03*
X463152Y839000D03*
X465121D03*
X467089D03*
X469058D03*
X471026D03*
Y853000D03*
X469058D03*
X467089D03*
X465121D03*
X463152D03*
G54D16*
X56000Y7500D03*
X57500Y993500D03*
X422678Y895000D03*
X483178Y821000D03*
X1322500Y69000D03*
X1367500Y995000D03*
G54D52*
X1368000Y457850D03*
G54D35*
X343929Y219050D03*
X356929Y219300D03*
X364909Y193719D03*
X365429Y219050D03*
X394029Y199700D03*
X385429Y223300D03*
X410729Y199800D03*
X407214Y199850D03*
X403109Y219580D03*
X438055Y322800D03*
X461929Y183800D03*
X451055Y381800D03*
Y389300D03*
X455778Y875800D03*
X471429Y129800D03*
X489555Y431300D03*
X678400Y402400D03*
X731716Y113084D03*
X735216D03*
X1149268Y679484D03*
X1144768Y681084D03*
X1157000Y680800D03*
X1154300Y806300D03*
X1160300Y804800D03*
X1165300D03*
X1170300D03*
X1200370Y708050D03*
X1217000Y202300D03*
X1220500D03*
X1273236Y690678D03*
X1277000Y709300D03*
X1273000Y727800D03*
X1292500Y409300D03*
X1312500Y611300D03*
X1306500Y648800D03*
X1379500Y322800D03*
G54D53*
X1368000Y455150D03*
G54D17*
X59504Y669720D03*
X60536Y693503D03*
Y690003D03*
X64972Y822004D03*
X77472Y730004D03*
X74472Y752504D03*
X70004Y853220D03*
X94504Y669720D03*
X95036Y694003D03*
Y690503D03*
X337129Y201500D03*
X348255Y538500D03*
Y542500D03*
X369689Y215420D03*
X377389Y215390D03*
X385069Y215400D03*
X405229Y165000D03*
X405129Y170500D03*
X412629D03*
X412729Y165000D03*
X405129Y183500D03*
Y177000D03*
X412629D03*
Y183500D03*
X405129Y190000D03*
X412629D03*
X427240Y139000D03*
X419740D03*
X420229Y165000D03*
X420129Y170500D03*
Y177000D03*
Y183500D03*
Y190000D03*
X434740Y139000D03*
X444255Y372500D03*
X455629Y118000D03*
X456755Y372500D03*
X464255D03*
X483629Y158500D03*
Y172500D03*
Y166000D03*
Y179000D03*
X487978Y832000D03*
X498655Y351500D03*
Y347500D03*
X522129Y141000D03*
X706916Y122784D03*
Y133284D03*
Y126284D03*
Y129784D03*
X1140668Y688284D03*
X1141800Y684800D03*
X1160800Y679300D03*
X1255700Y719500D03*
G54D26*
X301200Y98500D03*
X309200D03*
X349780Y179800D03*
X365129Y199389D03*
X383200Y901500D03*
Y906000D03*
X407200Y889500D03*
Y893500D03*
Y905500D03*
Y897500D03*
Y909500D03*
Y901500D03*
X428700Y314500D03*
X418223Y326283D03*
X426978Y828500D03*
Y837500D03*
Y842000D03*
Y833000D03*
Y846500D03*
Y851000D03*
Y860000D03*
Y855500D03*
X437083Y145701D03*
X430200Y241000D03*
Y245000D03*
X446740Y118000D03*
X449629Y113500D03*
X451629Y171500D03*
Y184500D03*
Y180000D03*
X468129Y104000D03*
X471129Y122000D03*
X477700Y140000D03*
X474129Y149000D03*
Y153500D03*
X474200Y144500D03*
X474700Y157500D03*
X474200Y162000D03*
X469700Y169000D03*
Y176000D03*
X465700Y286500D03*
X479731Y190291D03*
X491478Y857000D03*
Y852500D03*
Y861500D03*
X511629Y135000D03*
X527629Y129000D03*
X514629Y151000D03*
X780200Y968500D03*
X1010200Y66500D03*
X1039200Y145500D03*
X1063700Y124500D03*
X1081200Y640000D03*
X1088700D03*
X1135538Y688864D03*
X1225700Y722500D03*
X1253700Y641000D03*
Y647000D03*
X1261200D03*
X1253700Y657000D03*
Y651000D03*
Y661000D03*
Y667000D03*
Y675500D03*
Y679500D03*
Y691500D03*
Y695500D03*
Y699500D03*
Y703500D03*
Y707500D03*
Y711500D03*
X1251700Y715500D03*
Y719500D03*
X1259200Y715500D03*
X1344200Y399500D03*
G54D44*
X455278Y846000D03*
G54D54*
G01X-245081Y-422119D02*
G02I-12000J0D01*
G01X-250231D02*
G02I-6850J0D01*
G01X-241081D02*
X-273081D01*
G01X-257081Y-438119D02*
Y-406119D01*
G01X-241081Y-438119D02*
Y-518119D01*
G01D02*
X1034819D01*
G01X-241081Y-473619D02*
X1034819D01*
G01X-241081Y-438119D02*
X1034819D01*
G01X247319D02*
Y-518119D01*
G01X384819Y-438119D02*
Y-518119D01*
G01X499819Y-438119D02*
Y-518119D01*
G01X667319Y-438119D02*
Y-518119D01*
G01X837319Y-438119D02*
Y-518119D01*
G01X1034819Y-438119D02*
Y-518119D01*
G01X1066819Y-422119D02*
X1034819D01*
G01X1050819Y-438119D02*
Y-406119D01*
G01X1062819Y-422119D02*
G02I-12000J0D01*
G01X1057669D02*
G02I-6850J0D01*
G54D45*
X535000Y134750D03*
X531125Y142250D03*
X538875D03*
G54D27*
X313029Y219500D03*
X310829D03*
X313029Y222500D03*
X310829D03*
X359029Y128500D03*
X356829D03*
X359029Y124500D03*
X356829D03*
X362329Y146000D03*
X361329Y139500D03*
X365600Y134500D03*
X363400D03*
X365529Y131500D03*
X363329D03*
X364529Y146000D03*
X363529Y139500D03*
X391609Y148420D03*
X389409D03*
X415705Y346250D03*
X413505D03*
X444955Y326500D03*
X439855Y327200D03*
X437655D03*
X434055Y359370D03*
X431855D03*
X434100Y372000D03*
X431900D03*
X439755Y374700D03*
X437555D03*
X447155Y326500D03*
X453155Y342000D03*
X450955D03*
X461155Y404000D03*
X458955D03*
X467155Y326500D03*
X464955D03*
X477155Y338500D03*
X474955D03*
X476455Y344500D03*
X473655Y404000D03*
X471455D03*
X474655Y410000D03*
X472455D03*
X478655Y344500D03*
G54D18*
X63104Y669720D03*
X64136Y693503D03*
Y690003D03*
X81072Y730004D03*
X78072Y752504D03*
X68572Y822004D03*
X73604Y853220D03*
X98104Y669720D03*
X98636Y694003D03*
Y690503D03*
X340729Y201500D03*
X351855Y538500D03*
Y542500D03*
X373289Y215420D03*
X388669Y215400D03*
X380989Y215390D03*
X408829Y165000D03*
X408729Y170500D03*
Y183500D03*
Y177000D03*
Y190000D03*
X423340Y139000D03*
X423829Y165000D03*
X423729Y170500D03*
X416229D03*
X416329Y165000D03*
X423729Y177000D03*
X416229D03*
Y183500D03*
X423729D03*
Y190000D03*
X416229D03*
X438340Y139000D03*
X430840D03*
X459229Y118000D03*
X447855Y372500D03*
X460355D03*
X467855D03*
X487229Y158500D03*
Y172500D03*
Y166000D03*
Y179000D03*
X491578Y832000D03*
X502255Y351500D03*
Y347500D03*
X525729Y141000D03*
X710516Y122784D03*
Y133284D03*
Y126284D03*
Y129784D03*
X1144268Y688284D03*
X1145400Y684800D03*
X1164400Y679300D03*
X1259300Y719500D03*
G54D36*
X357940Y135500D03*
X360140D03*
X354440Y146000D03*
X356640D03*
X355940Y155000D03*
X358140D03*
X355940Y162000D03*
X358140D03*
X378229Y158600D03*
X378189Y164630D03*
X383400Y149500D03*
X385600D03*
X396029Y148500D03*
X380429Y158600D03*
X380389Y164630D03*
X401400Y148500D03*
X403600D03*
X406529Y151600D03*
X408729D03*
X398229Y148500D03*
X433155Y348900D03*
X435355D03*
X441055Y362700D03*
X443255D03*
X441055Y360400D03*
X443255D03*
X437155Y372000D03*
X439355D03*
X437055Y383900D03*
X439255D03*
X437055Y386300D03*
X439255D03*
X451055Y357800D03*
X453255D03*
X477423Y325583D03*
Y327983D03*
X472555Y347300D03*
X474755D03*
X472855Y364900D03*
X475055D03*
X472555Y374800D03*
X474755D03*
X472555Y372500D03*
X474755D03*
X472555Y383800D03*
X474755D03*
X479623Y325583D03*
Y327983D03*
X490455Y371500D03*
X492655D03*
X499255Y344400D03*
X501455D03*
X497455Y380000D03*
X499655D03*
X498955Y393000D03*
X501155D03*
X494955Y405500D03*
X497155D03*
X622640Y417801D03*
X624840D03*
X622640Y413401D03*
X624840D03*
X622640Y431001D03*
X624840D03*
X622640Y426601D03*
X624840D03*
X622640Y422201D03*
X624840D03*
X622640Y435401D03*
X624840D03*
G54D55*
G01X-185516Y-508119D02*
Y-490619D01*
G01X-176346D02*
Y-508119D01*
G01Y-499369D02*
X-185516D01*
G01X-163431Y-508119D02*
X-165178Y-507827D01*
X-166706Y-506661D01*
X-168016Y-504911D01*
X-168890Y-502869D01*
X-169326Y-500536D01*
Y-498202D01*
X-168890Y-495869D01*
X-168016Y-493827D01*
X-166706Y-492078D01*
X-165178Y-490911D01*
X-163431Y-490619D01*
X-161685Y-490911D01*
X-160156Y-492078D01*
X-158846Y-493827D01*
X-157972Y-495869D01*
X-157536Y-498202D01*
Y-500536D01*
X-157972Y-502869D01*
X-158846Y-504911D01*
X-160156Y-506661D01*
X-161685Y-507827D01*
X-163431Y-508119D01*
G01X-150953D02*
Y-490619D01*
X-140909Y-508119D01*
Y-490619D01*
G01X-124064Y-508119D02*
X-132798D01*
Y-490619D01*
X-124064D01*
G01X-127558Y-499077D02*
X-132798D01*
G01X-110931Y-508119D02*
Y-500244D01*
X-115298Y-490619D01*
G01X-106564D02*
X-110931Y-500244D01*
G01X-74185Y-498786D02*
X-73311Y-497911D01*
X-72656Y-496453D01*
X-72219Y-494410D01*
X-72656Y-492661D01*
X-73529Y-491494D01*
X-75058Y-490619D01*
X-80953D01*
Y-508119D01*
X-73748D01*
X-72219Y-506953D01*
X-71346Y-505202D01*
X-70909Y-503161D01*
X-71346Y-501119D01*
X-72656Y-499369D01*
X-74185Y-498786D01*
X-80953D01*
G01X-63890Y-508119D02*
X-58431Y-490619D01*
X-52972Y-508119D01*
G01X-54938Y-501994D02*
X-61925D01*
G01X-45734Y-508119D02*
Y-490619D01*
X-41368D01*
X-39621Y-491494D01*
X-38311Y-492661D01*
X-37219Y-494410D01*
X-36346Y-496453D01*
X-36128Y-499369D01*
X-36346Y-502286D01*
X-37219Y-504328D01*
X-38311Y-506078D01*
X-39621Y-507244D01*
X-41368Y-508119D01*
X-45734D01*
G01X-22121Y-499369D02*
X-17754D01*
Y-504619D01*
X-19064Y-506369D01*
X-20593Y-507536D01*
X-22776Y-508119D01*
X-24959Y-507536D01*
X-26488Y-506369D01*
X-27798Y-504619D01*
X-28671Y-502577D01*
X-29108Y-500244D01*
Y-498202D01*
X-28671Y-496453D01*
X-27798Y-494410D01*
X-26488Y-492661D01*
X-25178Y-491494D01*
X-23431Y-490619D01*
X-21903D01*
X-20156Y-491202D01*
X-18846Y-492369D01*
G01X-1564Y-508119D02*
X-10298D01*
Y-490619D01*
X-1564D01*
G01X-5058Y-499077D02*
X-10298D01*
G01X7202Y-508119D02*
Y-490619D01*
X12661D01*
X14407Y-491494D01*
X15499Y-492661D01*
X15936Y-494994D01*
X15499Y-497328D01*
X14189Y-498786D01*
X12661Y-499661D01*
X7202D01*
G01X12661D02*
X15936Y-508119D01*
G01X48315Y-498786D02*
X49189Y-497911D01*
X49844Y-496453D01*
X50281Y-494410D01*
X49844Y-492661D01*
X48971Y-491494D01*
X47442Y-490619D01*
X41547D01*
Y-508119D01*
X48752D01*
X50281Y-506953D01*
X51154Y-505202D01*
X51591Y-503161D01*
X51154Y-501119D01*
X49844Y-499369D01*
X48315Y-498786D01*
X41547D01*
G01X58610Y-508119D02*
X64069Y-490619D01*
X69528Y-508119D01*
G01X67562Y-501994D02*
X60575D01*
G01X76984Y-505786D02*
X78731Y-507244D01*
X80696Y-508119D01*
X82442D01*
X84189Y-507244D01*
X85499Y-505786D01*
X86154Y-503744D01*
X85717Y-501703D01*
X84626Y-499952D01*
X82661Y-498786D01*
X80041Y-498202D01*
X78512Y-497036D01*
X77857Y-494994D01*
X78294Y-492952D01*
X79386Y-491494D01*
X80914Y-490619D01*
X82442D01*
X83971Y-491202D01*
X85281Y-492661D01*
G01X103436Y-508119D02*
X94702D01*
Y-490619D01*
X103436D01*
G01X99942Y-499077D02*
X94702D01*
G01X118315Y-498786D02*
X119189Y-497911D01*
X119844Y-496453D01*
X120281Y-494410D01*
X119844Y-492661D01*
X118971Y-491494D01*
X117442Y-490619D01*
X111547D01*
Y-508119D01*
X118752D01*
X120281Y-506953D01*
X121154Y-505202D01*
X121591Y-503161D01*
X121154Y-501119D01*
X119844Y-499369D01*
X118315Y-498786D01*
X111547D01*
G01X134069Y-508119D02*
X132322Y-507827D01*
X130794Y-506661D01*
X129484Y-504911D01*
X128610Y-502869D01*
X128174Y-500536D01*
Y-498202D01*
X128610Y-495869D01*
X129484Y-493827D01*
X130794Y-492078D01*
X132322Y-490911D01*
X134069Y-490619D01*
X135815Y-490911D01*
X137344Y-492078D01*
X138654Y-493827D01*
X139528Y-495869D01*
X139964Y-498202D01*
Y-500536D01*
X139528Y-502869D01*
X138654Y-504911D01*
X137344Y-506661D01*
X135815Y-507827D01*
X134069Y-508119D01*
G01X146110D02*
X151569Y-490619D01*
X157028Y-508119D01*
G01X155062Y-501994D02*
X148075D01*
G01X164702Y-508119D02*
Y-490619D01*
X170161D01*
X171907Y-491494D01*
X172999Y-492661D01*
X173436Y-494994D01*
X172999Y-497328D01*
X171689Y-498786D01*
X170161Y-499661D01*
X164702D01*
G01X170161D02*
X173436Y-508119D01*
G01X181766D02*
Y-490619D01*
X186132D01*
X187879Y-491494D01*
X189189Y-492661D01*
X190281Y-494410D01*
X191154Y-496453D01*
X191372Y-499369D01*
X191154Y-502286D01*
X190281Y-504328D01*
X189189Y-506078D01*
X187879Y-507244D01*
X186132Y-508119D01*
X181766D01*
G01X-37858Y-463119D02*
Y-445619D01*
X-32181Y-460202D01*
X-26504Y-445619D01*
Y-463119D01*
G01X-14681D02*
X-15991Y-462827D01*
X-17301Y-461661D01*
X-18175Y-459619D01*
X-18611Y-457286D01*
X-18175Y-454952D01*
X-17301Y-452911D01*
X-15991Y-451744D01*
X-14681Y-451453D01*
X-13371Y-451744D01*
X-12061Y-452911D01*
X-11188Y-454952D01*
X-10969Y-457286D01*
X-11188Y-459619D01*
X-12061Y-461661D01*
X-13371Y-462827D01*
X-14681Y-463119D01*
G01X6749Y-445619D02*
Y-463119D01*
G01Y-460495D02*
X5876Y-461953D01*
X4565Y-462827D01*
X3037Y-463119D01*
X1291Y-462536D01*
X-19Y-461078D01*
X-893Y-459328D01*
X-1111Y-457286D01*
X-893Y-455244D01*
X-19Y-453494D01*
X1291Y-452036D01*
X3037Y-451453D01*
X4565Y-451744D01*
X5657Y-452328D01*
X6749Y-453494D01*
G01X17044Y-455244D02*
X24031D01*
X23376Y-453202D01*
X22284Y-452036D01*
X20756Y-451453D01*
X19227Y-451744D01*
X17917Y-452619D01*
X17044Y-454661D01*
X16607Y-456411D01*
Y-458161D01*
X17044Y-459911D01*
X18136Y-461661D01*
X19446Y-462827D01*
X20974Y-463119D01*
X22502Y-462536D01*
X24031Y-460786D01*
G01X37819Y-463119D02*
Y-445619D01*
G01X1Y-17717D02*
G03X7875Y-25591I7874J0D01*
G01X1Y299252D02*
Y-10394D01*
G01Y-17717D02*
G03X7875Y-25591I7874J0D01*
G01X1Y299252D02*
Y-10394D01*
G01Y-17717D02*
Y-10394D01*
G01D02*
Y-17723D01*
G01X0Y11811D02*
Y0D01*
G01X92520Y299252D02*
X1D01*
G01X92520D02*
X1D01*
G01X0Y318937D02*
G03X11811Y307126I11811J0D01*
G01X0Y968503D02*
Y318937D01*
G01X19685Y988189D02*
G03X0Y968503I0J-19685D01*
G01X43950Y996063D02*
X1D01*
G01X43950D02*
X1D01*
G01Y1008622D02*
Y996063D01*
G01Y1008622D02*
Y996063D01*
G01X15001Y1023622D02*
G03X1Y1008622I0J-15000D01*
G01X15001Y1023622D02*
G03X1Y1008622I0J-15000D01*
G01X7875Y-25591D02*
X45337D01*
G01X7875D02*
X45337D01*
G01X11811Y307126D02*
X100394D01*
G01X10710Y1008622D02*
G03X19292I4291J0D01*
G01D02*
G03X10710I-4291J0D01*
G01X99804Y1023622D02*
X15001D01*
G01X99804D02*
X15001D01*
G01X103740Y988189D02*
X19685D01*
G01X53211Y-25591D02*
G03X45337I-3937J0D01*
G01X53211D02*
G03X45337I-3937J0D01*
G01X53211D02*
G03X45337I-3937J0D01*
G01X53211D02*
G03X45337I-3937J0D01*
G01X43950Y988189D02*
G03Y996063I0J3937D01*
G01Y988189D02*
G03Y996063I0J3937D01*
G01X53211Y-25591D02*
X1392127D01*
G01X53211D02*
X1392127D01*
G01X69147Y996063D02*
G03Y988189I0J-3937D01*
G01Y996063D02*
G03Y988189I0J-3937D01*
G01X99804Y996063D02*
X69147D01*
G01X99804D02*
X69147D01*
G01X94412Y72220D02*
G03X85830Y72219I-4291J-1D01*
G01D02*
G03X94412Y72220I4291J0D01*
G01X100394Y291377D02*
G03X92520Y299252I-7874J1D01*
G01X100394Y291377D02*
G03X92520Y299252I-7874J1D01*
G01X99804Y1023622D02*
Y996063D01*
G01Y1023622D02*
Y996063D01*
G01X100394Y236259D02*
G03X116142Y220511I15748J0D01*
G01D02*
X232088D01*
G01X100394Y236259D02*
G03X116142Y220511I15748J0D01*
G01D02*
X232088D01*
G01X116142Y228385D02*
X239961D01*
G01X108268Y236259D02*
G03X116142Y228385I7874J0D01*
G01X108268Y299252D02*
Y236259D01*
G01X100395Y240899D02*
X100394Y236259D01*
G01X100395Y240899D02*
X100394Y236259D01*
G01X108269Y240899D02*
G03X100395I-3937J0D01*
G01X108269D02*
G03X100395I-3937J0D01*
G01Y266096D02*
G03X108269I3937J-1D01*
G01X100395D02*
G03X108269I3937J-1D01*
G01X100395D02*
X100394Y291377D01*
G01X100395Y266096D02*
X100394Y291377D01*
G01X108268Y299252D02*
G03X100394Y307126I-7874J0D01*
G01X103740Y988189D02*
G03X107677Y992126I0J3937D01*
G01Y1018109D02*
Y992126D01*
G01X136024Y1018109D02*
X136023Y1021653D01*
X134055Y1023622D01*
X109645D01*
X107677Y1021653D01*
Y1018109D01*
G01X136024Y994290D02*
G03X143505I3740J0D01*
G01X136024D02*
Y1018109D01*
G01X143504D02*
Y994290D01*
G01X187598Y1018109D02*
Y1021653D01*
X185630Y1023622D01*
X145472D01*
X143504Y1021653D01*
Y1018109D01*
G01X151575Y220511D02*
X226378D01*
G01X151575D02*
X226378D01*
G01X187598Y992126D02*
Y1018109D01*
G01Y992126D02*
G03X191535Y988189I3937J0D01*
G01X261220D02*
X191535D01*
G01X212681Y996063D02*
X195473D01*
G01D02*
Y1023622D01*
G01X212681Y996063D02*
X195473D01*
G01D02*
Y1023622D01*
G01D02*
X257284D01*
G01X195473D02*
X257284D01*
G01X212681Y988189D02*
G03Y996063I0J3937D01*
G01Y988189D02*
G03Y996063I0J3937D01*
G01X222751Y1008622D02*
G03X231333I4291J0D01*
G01D02*
G03X222751I-4291J0D01*
G01X243898Y70866D02*
G03X247835Y66928I3937J-1D01*
G01X243898Y224448D02*
Y70866D01*
G01X236025Y164487D02*
Y70866D01*
G01D02*
G03X247836Y59055I11811J0D01*
G01X236025Y164487D02*
Y70866D01*
G01D02*
G03X247836Y59055I11811J0D01*
G01X243899Y164487D02*
G03X236025I-3937J0D01*
G01X243899D02*
G03X236025I-3937J0D01*
G01Y189684D02*
G03X243899I3937J0D01*
G01X236025D02*
G03X243899I3937J0D01*
G01X236025D02*
Y216574D01*
G01Y189684D02*
Y216574D01*
G01D02*
G03X232088Y220511I-3937J0D01*
G01X236025Y216574D02*
G03X232088Y220511I-3937J0D01*
G01X243898Y224448D02*
G03X239961Y228385I-3937J0D01*
G01X237877Y996063D02*
G03Y988189I0J-3937D01*
G01Y996063D02*
G03Y988189I0J-3937D01*
G01X257284Y996063D02*
X237877D01*
G01X257284D02*
X237877D01*
G01X247835Y66929D02*
X289174D01*
G01X247836Y59055D02*
X285237D01*
G01X247836D02*
X285237D01*
G01X261220Y988189D02*
G03X265157Y992126I0J3937D01*
G01X257284Y1023622D02*
Y996063D01*
G01Y1023622D02*
Y996063D01*
G01X281019Y-508119D02*
Y-490619D01*
X278399Y-494119D01*
G01Y-508119D02*
X283639D01*
G01X293716Y-504619D02*
X295025Y-506661D01*
X296772Y-507827D01*
X298737Y-508119D01*
X300484Y-507827D01*
X302231Y-506369D01*
X303322Y-504619D01*
X303541Y-502869D01*
X303104Y-500828D01*
X301576Y-499369D01*
X300047Y-498786D01*
X298082D01*
G01X300047D02*
X301357Y-497911D01*
X302449Y-496453D01*
X302886Y-494703D01*
X302449Y-492952D01*
X301357Y-491494D01*
X299392Y-490619D01*
X297427Y-490911D01*
X295462Y-492078D01*
G01X312307Y-506078D02*
X313836Y-507536D01*
X315582Y-508119D01*
X317329Y-507536D01*
X318857Y-505786D01*
X319949Y-503161D01*
X320386Y-500536D01*
Y-497328D01*
X319949Y-494703D01*
X318857Y-492369D01*
X317547Y-491202D01*
X316019Y-490619D01*
X314272Y-491202D01*
X312962Y-492369D01*
X312089Y-494119D01*
X311652Y-496453D01*
X312089Y-498494D01*
X313181Y-500536D01*
X314491Y-501703D01*
X316019Y-501994D01*
X317765Y-501411D01*
X319076Y-499952D01*
X320386Y-497328D01*
G01X336139Y-508119D02*
Y-490619D01*
X328060Y-503161D01*
X338978D01*
G01X351019Y-508119D02*
X352547Y-507827D01*
X354294Y-506953D01*
X355386Y-505495D01*
X355822Y-503452D01*
X355386Y-501411D01*
X354076Y-499661D01*
X352111Y-498786D01*
X349927D01*
X348617Y-498202D01*
X347525Y-496744D01*
X347089Y-494703D01*
X347744Y-492661D01*
X349272Y-491202D01*
X351019Y-490619D01*
X352765Y-491202D01*
X354294Y-492661D01*
X354949Y-494703D01*
X354512Y-496744D01*
X353421Y-498202D01*
X352111Y-498786D01*
X349927D01*
X347962Y-499661D01*
X346652Y-501411D01*
X346216Y-503452D01*
X346652Y-505495D01*
X347744Y-506953D01*
X349491Y-507827D01*
X351019Y-508119D01*
G01X267902Y-463119D02*
Y-445619D01*
X273142D01*
X274889Y-446494D01*
X276199Y-448536D01*
X276636Y-450869D01*
X276199Y-453202D01*
X275107Y-454952D01*
X273142Y-455828D01*
X267902D01*
G01X294572Y-447078D02*
X293262Y-446202D01*
X291734Y-445619D01*
X289987D01*
X288022Y-446494D01*
X286494Y-447952D01*
X285402Y-449703D01*
X284529Y-452619D01*
X284310Y-455244D01*
X284747Y-457869D01*
X285402Y-459619D01*
X286712Y-461369D01*
X288241Y-462536D01*
X289769Y-463119D01*
X291297D01*
X292826Y-462536D01*
X294136Y-461661D01*
X295228Y-460495D01*
G01X309015Y-453786D02*
X309889Y-452911D01*
X310544Y-451453D01*
X310981Y-449410D01*
X310544Y-447661D01*
X309671Y-446494D01*
X308142Y-445619D01*
X302247D01*
Y-463119D01*
X309452D01*
X310981Y-461953D01*
X311854Y-460202D01*
X312291Y-458161D01*
X311854Y-456119D01*
X310544Y-454369D01*
X309015Y-453786D01*
X302247D01*
G01X318219Y-468952D02*
X331319D01*
G01X337247Y-463119D02*
Y-445619D01*
X347291Y-463119D01*
Y-445619D01*
G01X359769Y-463119D02*
X358022Y-462827D01*
X356494Y-461661D01*
X355184Y-459911D01*
X354310Y-457869D01*
X353874Y-455536D01*
Y-453202D01*
X354310Y-450869D01*
X355184Y-448827D01*
X356494Y-447078D01*
X358022Y-445911D01*
X359769Y-445619D01*
X361515Y-445911D01*
X363044Y-447078D01*
X364354Y-448827D01*
X365228Y-450869D01*
X365664Y-453202D01*
Y-455536D01*
X365228Y-457869D01*
X364354Y-459911D01*
X363044Y-461661D01*
X361515Y-462827D01*
X359769Y-463119D01*
G01X265157Y1018109D02*
Y992126D01*
G01X545472Y1018109D02*
Y1021653D01*
X543504Y1023622D01*
X267126D01*
X265157Y1021653D01*
Y1018109D01*
G01X293111Y3937D02*
G03X297047Y0I3937J0D01*
G01X293110Y62992D02*
Y3937D01*
G01X285237D02*
G03X297048Y-7874I11811J0D01*
G01X285237Y59055D02*
Y3937D01*
G01D02*
G03X297048Y-7874I11811J0D01*
G01X285237Y59055D02*
Y3937D01*
G01X293111Y62992D02*
G03X289174Y66929I-3937J0D01*
G01X297047Y0D02*
X1108209D01*
G01X297037Y-7874D02*
X301187D01*
G01D02*
G03Y0I0J3937D01*
G01X297037Y-7874D02*
X301187D01*
G01D02*
G03Y0I0J3937D01*
G01X318510Y-7874D02*
X515333D01*
G01X318510Y0D02*
G03Y-7874I0J-3937D01*
G01D02*
X515333D01*
G01X318510Y0D02*
G03Y-7874I0J-3937D01*
G01X410610Y-445619D02*
X416069Y-463119D01*
X421528Y-445619D01*
G01X437936Y-463119D02*
X429202D01*
Y-445619D01*
X437936D01*
G01X434442Y-454077D02*
X429202D01*
G01X446702Y-463119D02*
Y-445619D01*
X452161D01*
X453907Y-446494D01*
X454999Y-447661D01*
X455436Y-449994D01*
X454999Y-452328D01*
X453689Y-453786D01*
X452161Y-454661D01*
X446702D01*
G01X452161D02*
X455436Y-463119D01*
G01X468569Y-463702D02*
X468132Y-463411D01*
Y-462827D01*
X468569Y-462536D01*
X469006Y-462827D01*
Y-463411D01*
X468569Y-463702D01*
G01X433569Y-508119D02*
Y-490619D01*
X430949Y-494119D01*
G01Y-508119D02*
X436189D01*
G01X452815Y-498786D02*
X453689Y-497911D01*
X454344Y-496453D01*
X454781Y-494410D01*
X454344Y-492661D01*
X453471Y-491494D01*
X451942Y-490619D01*
X446047D01*
Y-508119D01*
X453252D01*
X454781Y-506953D01*
X455654Y-505202D01*
X456091Y-503161D01*
X455654Y-501119D01*
X454344Y-499369D01*
X452815Y-498786D01*
X446047D01*
G01X515302Y-7874D02*
G03Y0I0J3937D01*
G01Y-7874D02*
G03Y0I0J3937D01*
G01X544152Y-445619D02*
Y-463119D01*
X552886D01*
G01X569949D02*
Y-451453D01*
G01Y-453494D02*
X569076Y-452328D01*
X567765Y-451744D01*
X566237Y-451453D01*
X564709Y-452036D01*
X563399Y-453202D01*
X562525Y-454952D01*
X562089Y-457286D01*
X562525Y-459619D01*
X563399Y-461369D01*
X564709Y-462536D01*
X566237Y-463119D01*
X567765Y-462827D01*
X569076Y-461953D01*
X569949Y-460786D01*
G01X578934Y-468369D02*
X580244Y-468952D01*
X581991Y-468369D01*
X583082Y-467203D01*
X583956Y-465744D01*
X585265Y-461078D01*
X588104Y-451453D01*
G01X581117D02*
X585265Y-461078D01*
G01X597744Y-455244D02*
X604731D01*
X604076Y-453202D01*
X602984Y-452036D01*
X601456Y-451453D01*
X599927Y-451744D01*
X598617Y-452619D01*
X597744Y-454661D01*
X597307Y-456411D01*
Y-458161D01*
X597744Y-459911D01*
X598836Y-461661D01*
X600146Y-462827D01*
X601674Y-463119D01*
X603202Y-462536D01*
X604731Y-460786D01*
G01X615462Y-463119D02*
Y-451453D01*
G01Y-453786D02*
X616554Y-452619D01*
X617646Y-451744D01*
X619174Y-451453D01*
X620265Y-451744D01*
X621576Y-452619D01*
G01X540499Y-7874D02*
X727049D01*
G01X540499Y0D02*
G03Y-7874I0J-3937D01*
G01D02*
X727049D01*
G01X540499Y0D02*
G03Y-7874I0J-3937D01*
G01X608023Y-498786D02*
X607149Y-497911D01*
X606494Y-496453D01*
X606057Y-494410D01*
X606494Y-492661D01*
X607367Y-491494D01*
X608896Y-490619D01*
X614791D01*
Y-508119D01*
X607586D01*
X606057Y-506953D01*
X605184Y-505202D01*
X604747Y-503161D01*
X605184Y-501119D01*
X606494Y-499369D01*
X608023Y-498786D01*
X614791D01*
G01X596854Y-505786D02*
X595107Y-507244D01*
X593142Y-508119D01*
X591396D01*
X589649Y-507244D01*
X588339Y-505786D01*
X587684Y-503744D01*
X588121Y-501703D01*
X589212Y-499952D01*
X591177Y-498786D01*
X593797Y-498202D01*
X595326Y-497036D01*
X595981Y-494994D01*
X595544Y-492952D01*
X594452Y-491494D01*
X592924Y-490619D01*
X591396D01*
X589867Y-491202D01*
X588557Y-492661D01*
G01X580446Y-508119D02*
Y-490619D01*
X574769Y-505202D01*
X569092Y-490619D01*
Y-508119D01*
G01X562072D02*
Y-490619D01*
X557706D01*
X555959Y-491494D01*
X554649Y-492661D01*
X553557Y-494410D01*
X552684Y-496453D01*
X552466Y-499369D01*
X552684Y-502286D01*
X553557Y-504328D01*
X554649Y-506078D01*
X555959Y-507244D01*
X557706Y-508119D01*
X562072D01*
G01X545472Y994290D02*
G03X552953I3740J1D01*
G01X545472D02*
Y1018109D01*
G01X552953D02*
Y994290D01*
G01X597047Y1018109D02*
Y1021653D01*
X595078Y1023622D01*
X554921D01*
X552952Y1021653D01*
X552953Y1018109D01*
G01X597047Y992126D02*
Y1018109D01*
G01X597048Y992126D02*
G03X600984Y988189I3937J0D01*
G01X713189D02*
X600984D01*
G01X641198Y996063D02*
X604922D01*
G01D02*
Y1023622D01*
G01X641198Y996063D02*
X604922D01*
G01D02*
Y1023622D01*
G01D02*
X709253D01*
G01X604922D02*
X709253D01*
G01X641198Y988189D02*
G03Y996063I0J3937D01*
G01Y988189D02*
G03Y996063I0J3937D01*
G01X649684Y1008622D02*
G03X658266I4291J0D01*
G01D02*
G03X649684I-4291J0D01*
G01X666395Y996063D02*
G03Y988189I0J-3937D01*
G01Y996063D02*
G03Y988189I0J-3937D01*
G01X709253Y996063D02*
X666395D01*
G01X709253D02*
X666395D01*
G01X686702Y-490619D02*
Y-508119D01*
X695436D01*
G01X703984Y-513369D02*
X705294Y-513952D01*
X707041Y-513369D01*
X708132Y-512203D01*
X709006Y-510744D01*
X710315Y-506078D01*
X713154Y-496453D01*
G01X706167D02*
X710315Y-506078D01*
G01X722357Y-508119D02*
Y-496453D01*
G01Y-499369D02*
X723231Y-497911D01*
X724541Y-496744D01*
X726287Y-496453D01*
X727815Y-496744D01*
X729126Y-497911D01*
X729781Y-499952D01*
Y-508119D01*
G01X739857D02*
Y-496453D01*
G01Y-499369D02*
X740731Y-497911D01*
X742041Y-496744D01*
X743787Y-496453D01*
X745315Y-496744D01*
X746626Y-497911D01*
X747281Y-499952D01*
Y-508119D01*
G01X774202Y-490619D02*
Y-508119D01*
X782936D01*
G01X796069Y-496453D02*
Y-508119D01*
G01Y-491786D02*
X795632Y-491494D01*
Y-490911D01*
X796069Y-490619D01*
X796506Y-490911D01*
Y-491494D01*
X796069Y-491786D01*
G01X809857Y-496453D02*
Y-504619D01*
X810731Y-506661D01*
X812041Y-507827D01*
X813569Y-508119D01*
X815097Y-507827D01*
X816407Y-506661D01*
X817281Y-504619D01*
G01Y-508119D02*
Y-496453D01*
G01X686266Y-463119D02*
Y-445619D01*
X690632D01*
X692379Y-446494D01*
X693689Y-447661D01*
X694781Y-449410D01*
X695654Y-451453D01*
X695872Y-454369D01*
X695654Y-457286D01*
X694781Y-459328D01*
X693689Y-461078D01*
X692379Y-462244D01*
X690632Y-463119D01*
X686266D01*
G01X705294Y-455244D02*
X712281D01*
X711626Y-453202D01*
X710534Y-452036D01*
X709006Y-451453D01*
X707477Y-451744D01*
X706167Y-452619D01*
X705294Y-454661D01*
X704857Y-456411D01*
Y-458161D01*
X705294Y-459911D01*
X706386Y-461661D01*
X707696Y-462827D01*
X709224Y-463119D01*
X710752Y-462536D01*
X712281Y-460786D01*
G01X722794Y-461078D02*
X723886Y-462244D01*
X725414Y-463119D01*
X726724D01*
X728034Y-462536D01*
X728907Y-461661D01*
X729344Y-460495D01*
X729126Y-458744D01*
X728252Y-457869D01*
X724322Y-456119D01*
X723449Y-454077D01*
X723886Y-452619D01*
X724759Y-451744D01*
X726069Y-451453D01*
X727379Y-451744D01*
X728689Y-452619D01*
G01X743569Y-451453D02*
Y-463119D01*
G01Y-446786D02*
X743132Y-446494D01*
Y-445911D01*
X743569Y-445619D01*
X744006Y-445911D01*
Y-446494D01*
X743569Y-446786D01*
G01X758012Y-467494D02*
X759541Y-468661D01*
X761287Y-468952D01*
X762815Y-468661D01*
X764126Y-467203D01*
X764999Y-465161D01*
Y-451453D01*
G01Y-453786D02*
X764126Y-452619D01*
X762815Y-451744D01*
X761287Y-451453D01*
X759541Y-452036D01*
X758449Y-453202D01*
X757575Y-455244D01*
X757139Y-457286D01*
X757357Y-459036D01*
X758231Y-461078D01*
X759541Y-462536D01*
X761287Y-463119D01*
X762597Y-462827D01*
X764126Y-461661D01*
X764999Y-460495D01*
G01X774857Y-463119D02*
Y-451453D01*
G01Y-454369D02*
X775731Y-452911D01*
X777041Y-451744D01*
X778787Y-451453D01*
X780315Y-451744D01*
X781626Y-452911D01*
X782281Y-454952D01*
Y-463119D01*
G01X792794Y-455244D02*
X799781D01*
X799126Y-453202D01*
X798034Y-452036D01*
X796506Y-451453D01*
X794977Y-451744D01*
X793667Y-452619D01*
X792794Y-454661D01*
X792357Y-456411D01*
Y-458161D01*
X792794Y-459911D01*
X793886Y-461661D01*
X795196Y-462827D01*
X796724Y-463119D01*
X798252Y-462536D01*
X799781Y-460786D01*
G01X810512Y-463119D02*
Y-451453D01*
G01Y-453786D02*
X811604Y-452619D01*
X812696Y-451744D01*
X814224Y-451453D01*
X815315Y-451744D01*
X816626Y-452619D01*
G01X713189Y988189D02*
G03X717126Y992126I0J3937D01*
G01Y1018109D02*
Y992126D01*
G01X709253Y1023622D02*
Y996063D01*
G01Y1023622D02*
Y996063D01*
G01X745472Y1018109D02*
Y1021653D01*
X743504Y1023622D01*
X719094D01*
X717126Y1021653D01*
Y1018109D01*
G01X727049Y-7874D02*
G03Y0I0J3937D01*
G01Y-7874D02*
G03Y0I0J3937D01*
G01X752246Y-7874D02*
X984201D01*
G01X752246Y0D02*
G03Y-7874I0J-3937D01*
G01D02*
X984201D01*
G01X752246Y0D02*
G03Y-7874I0J-3937D01*
G01X745472Y994290D02*
G03X752953I3741J1D01*
G01X745472D02*
Y1018109D01*
G01X752953D02*
Y994290D01*
G01X797047Y1018109D02*
Y1021653D01*
X795078Y1023622D01*
X754921D01*
X752952Y1021653D01*
X752953Y1018109D01*
G01X797047Y992126D02*
Y1018109D01*
G01X797048Y992126D02*
G03X800984Y988189I3937J0D01*
G01X902165D02*
X800984D01*
G01X859109Y996063D02*
X804922D01*
G01D02*
Y1023622D01*
G01X859109Y996063D02*
X804922D01*
G01D02*
Y1023622D01*
G01D02*
X1325399D01*
G01X804922D02*
X1325399D01*
G01X857269Y-508119D02*
Y-490619D01*
X854649Y-494119D01*
G01Y-508119D02*
X859889D01*
G01X874769D02*
Y-490619D01*
X872149Y-494119D01*
G01Y-508119D02*
X877389D01*
G01X888339Y-508702D02*
X896199Y-490619D01*
G01X909769Y-508119D02*
Y-490619D01*
X907149Y-494119D01*
G01Y-508119D02*
X912389D01*
G01X922466Y-504619D02*
X923775Y-506661D01*
X925522Y-507827D01*
X927487Y-508119D01*
X929234Y-507827D01*
X930981Y-506369D01*
X932072Y-504619D01*
X932291Y-502869D01*
X931854Y-500828D01*
X930326Y-499369D01*
X928797Y-498786D01*
X926832D01*
G01X928797D02*
X930107Y-497911D01*
X931199Y-496453D01*
X931636Y-494703D01*
X931199Y-492952D01*
X930107Y-491494D01*
X928142Y-490619D01*
X926177Y-490911D01*
X924212Y-492078D01*
G01X940839Y-508702D02*
X948699Y-490619D01*
G01X958121Y-493536D02*
X959431Y-491786D01*
X960959Y-490911D01*
X962706Y-490619D01*
X964889Y-491202D01*
X966417Y-492661D01*
X966854Y-494410D01*
X966636Y-496161D01*
X965762Y-497619D01*
X961396Y-500536D01*
X959431Y-502577D01*
X958121Y-505495D01*
X957684Y-508119D01*
X966854D01*
G01X979769Y-490619D02*
X978022Y-491202D01*
X976712Y-492661D01*
X975839Y-494410D01*
X975184Y-496744D01*
X974966Y-499369D01*
X975184Y-501994D01*
X975839Y-504328D01*
X976712Y-506078D01*
X978022Y-507536D01*
X979769Y-508119D01*
X981515Y-507536D01*
X982826Y-506078D01*
X983699Y-504328D01*
X984354Y-501994D01*
X984572Y-499369D01*
X984354Y-496744D01*
X983699Y-494410D01*
X982826Y-492661D01*
X981515Y-491202D01*
X979769Y-490619D01*
G01X997269Y-508119D02*
Y-490619D01*
X994649Y-494119D01*
G01Y-508119D02*
X999889D01*
G01X1017389D02*
Y-490619D01*
X1009310Y-503161D01*
X1020228D01*
G01X859109Y988189D02*
G03Y996063I0J3937D01*
G01Y988189D02*
G03Y996063I0J3937D01*
G01X884306D02*
G03Y988189I0J-3937D01*
G01Y996063D02*
G03Y988189I0J-3937D01*
G01X902166Y996063D02*
X884306D01*
G01X902166D02*
X884306D01*
G01X904966Y-463119D02*
Y-445619D01*
X909332D01*
X911079Y-446494D01*
X912389Y-447661D01*
X913481Y-449410D01*
X914354Y-451453D01*
X914572Y-454369D01*
X914354Y-457286D01*
X913481Y-459328D01*
X912389Y-461078D01*
X911079Y-462244D01*
X909332Y-463119D01*
X904966D01*
G01X931199D02*
Y-451453D01*
G01Y-453494D02*
X930326Y-452328D01*
X929015Y-451744D01*
X927487Y-451453D01*
X925959Y-452036D01*
X924649Y-453202D01*
X923775Y-454952D01*
X923339Y-457286D01*
X923775Y-459619D01*
X924649Y-461369D01*
X925959Y-462536D01*
X927487Y-463119D01*
X929015Y-462827D01*
X930326Y-461953D01*
X931199Y-460786D01*
G01X944769Y-445619D02*
Y-463119D01*
G01X941712Y-451453D02*
X947826D01*
G01X958994Y-455244D02*
X965981D01*
X965326Y-453202D01*
X964234Y-452036D01*
X962706Y-451453D01*
X961177Y-451744D01*
X959867Y-452619D01*
X958994Y-454661D01*
X958557Y-456411D01*
Y-458161D01*
X958994Y-459911D01*
X960086Y-461661D01*
X961396Y-462827D01*
X962924Y-463119D01*
X964452Y-462536D01*
X965981Y-460786D01*
G01X921850Y968503D02*
G03X902165Y988189I-19685J1D01*
G01X929725Y968504D02*
G03X902166Y996063I-27559J0D01*
G01D02*
X902195D01*
G01X929725Y968504D02*
G03X902166Y996063I-27559J0D01*
G01D02*
X902195D01*
G01X921850Y775590D02*
Y968503D01*
G01Y775590D02*
G03X925787Y771653I3937J0D01*
G01X984843D02*
X925787D01*
G01X929725Y779527D02*
Y886881D01*
G01Y779527D02*
X980906D01*
G01X929725D02*
Y886881D01*
G01Y779527D02*
X980906D01*
G01X929725Y886881D02*
G03X921851I-3937J1D01*
G01X929725D02*
G03X921851I-3937J1D01*
G01Y912079D02*
G03X929725I3937J-1D01*
G01X921851D02*
G03X929725I3937J-1D01*
G01Y912078D02*
Y968504D01*
G01Y912078D02*
Y968504D01*
G01X959606Y850829D02*
G03X951024I-4291J0D01*
G01D02*
G03X959606I4291J0D01*
G01X984201Y-7874D02*
G03Y0I0J3937D01*
G01Y-7874D02*
G03Y0I0J3937D01*
G01X984843Y771653D02*
G03X988780Y775590I0J3937D01*
G01X980907Y886881D02*
X980906Y779527D01*
G01X980907Y886881D02*
X980906Y779527D01*
G01X988781Y886881D02*
G03X980907I-3937J1D01*
G01X988781D02*
G03X980907I-3937J1D01*
G01Y912079D02*
G03X988781I3937J-1D01*
G01X980907D02*
G03X988781I3937J-1D01*
G01X980907D02*
X980906Y968504D01*
G01X980907Y912079D02*
X980906Y968504D01*
G01X1008465Y996063D02*
G03X980906Y968504I0J-27559D01*
G01X1008465Y996063D02*
G03X980906Y968504I0J-27559D01*
G01X988780Y968503D02*
Y775590D01*
G01X1008465Y988189D02*
G03X988780Y968503I0J-19685D01*
G01X1009398Y-7874D02*
X1108229D01*
G01X1009398Y0D02*
G03Y-7874I-1J-3937D01*
G01D02*
X1108229D01*
G01X1009398Y0D02*
G03Y-7874I-1J-3937D01*
G01X1380315Y988189D02*
X1008465D01*
G01X1070592Y996063D02*
X1008466D01*
G01X1070592D02*
X1008466D01*
G01X1070592Y988189D02*
G03Y996063I0J3937D01*
G01Y988189D02*
G03Y996063I0J3937D01*
G01X1095789D02*
G03Y988189I0J-3937D01*
G01Y996063D02*
G03Y988189I0J-3937D01*
G01X1325399Y996063D02*
X1095789D01*
G01X1325399D02*
X1095789D01*
G01X1112146Y3937D02*
Y210629D01*
G01X1108209Y0D02*
G03X1112146Y3937I0J3937D01*
G01X1108208Y-7874D02*
G03X1120020Y3938I1J11811D01*
G01X1108208Y-7874D02*
G03X1120020Y3938I1J11811D01*
G01Y99950D02*
G03X1112146I-3937J0D01*
G01X1120020D02*
G03X1112146I-3937J0D01*
G01Y125147D02*
G03X1120020I3937J0D01*
G01X1112146D02*
G03X1120020I3937J0D01*
G01X1116083Y214566D02*
X1194824D01*
G01X1116083D02*
G03X1112146Y210629I0J-3937D01*
G01X1120020Y99950D02*
Y3938D01*
G01Y99950D02*
Y3938D01*
G01Y125147D02*
Y206693D01*
G01Y125147D02*
Y206693D01*
G01X1120021D02*
X1190887D01*
G01X1120021D02*
X1190887D01*
G01X1161386Y128841D02*
G03X1152804I-4291J0D01*
G01D02*
G03X1161386I4291J0D01*
G01X1198760Y3937D02*
G03X1210571Y-7874I11811J0D01*
G01X1198760Y3937D02*
G03X1210571Y-7874I11811J0D01*
G01X1198761Y97100D02*
X1198760Y3937D01*
G01X1198761Y97100D02*
X1198760Y3937D01*
G01X1206635Y97100D02*
G03X1198761I-3937J0D01*
G01X1206635D02*
G03X1198761I-3937J0D01*
G01Y122297D02*
G03X1206635I3937J0D01*
G01X1198761D02*
G03X1206635I3937J0D01*
G01X1198761D02*
Y168002D01*
G01Y122297D02*
Y168002D01*
G01X1190887Y179134D02*
G03X1198761Y167998I11811J0D01*
G01X1190887Y179134D02*
G03X1198761Y167998I11811J0D01*
G01X1198760Y179133D02*
G03X1202697Y175196I3937J0D01*
G01X1198760Y210629D02*
Y179133D01*
G01X1190887Y206693D02*
Y179134D01*
G01Y206693D02*
Y179134D01*
G01X1198760Y210629D02*
G03X1194824Y214566I-3937J0D01*
G01X1210571Y0D02*
X1396063D01*
G01X1206634Y3937D02*
G03X1210571Y0I3937J0D01*
G01X1206634Y171259D02*
Y3937D01*
G01X1210552Y-7874D02*
X1210572D01*
G01D02*
G03Y0I0J3937D01*
G01X1210552Y-7874D02*
X1210572D01*
G01D02*
G03Y0I0J3937D01*
G01X1206634Y171259D02*
G03X1202697Y175196I-3937J0D01*
G01X1226320Y-7874D02*
X1380317D01*
G01X1226320Y0D02*
G03Y-7874I0J-3937D01*
G01D02*
X1380317D01*
G01X1226320Y0D02*
G03Y-7874I0J-3937D01*
G01X1354801Y996063D02*
X1325399D01*
G01X1354801D02*
X1325399D01*
G01Y1023622D02*
X1385001D01*
G01X1325399D02*
X1385001D01*
G01X1354801Y988189D02*
G03Y996063I0J3937D01*
G01Y988189D02*
G03Y996063I0J3937D01*
G01X1380316Y-7874D02*
G03Y0I0J3937D01*
G01Y-7874D02*
G03Y0I0J3937D01*
G01X1400000Y968503D02*
G03X1380315Y988189I-19685J1D01*
G01X1379998Y996063D02*
G03Y988189I0J-3937D01*
G01Y996063D02*
G03Y988189I0J-3937D01*
G01X1400001Y996063D02*
X1379998D01*
G01X1400001D02*
X1379998D01*
G01X1392127Y-25591D02*
G03X1400001Y-17717I0J7874D01*
G01X1392167Y-15015D02*
G03X1383585I-4291J0D01*
G01D02*
G03X1392167I4291J0D01*
G01X1392127Y-25591D02*
G03X1400001Y-17717I0J7874D01*
G01X1396063Y0D02*
G03X1400000Y3937I0J3937D01*
G01X1396064Y-7874D02*
X1400001D01*
G01X1396064Y0D02*
G03Y-7874I0J-3937D01*
G01D02*
X1400001D01*
G01X1396064Y0D02*
G03Y-7874I0J-3937D01*
G01X1380710Y1008622D02*
G03X1389292I4291J0D01*
G01D02*
G03X1380710I-4291J0D01*
G01X1400001D02*
G03X1385001Y1023622I-15000J0D01*
G01X1400001Y1008622D02*
G03X1385001Y1023622I-15000J0D01*
G01X1400001Y-17717D02*
Y-7874D01*
G01Y-17717D02*
Y-7874D01*
G01X1400000Y3937D02*
Y968503D01*
G01X1400001Y996063D02*
Y1008622D01*
G01Y996063D02*
Y1008622D01*
G54D19*
X83788Y853252D03*
X119504Y796720D03*
Y800720D03*
X387129Y170500D03*
Y174000D03*
X386700Y197200D03*
Y200600D03*
X387200Y190000D03*
X395759Y215180D03*
X412240Y139000D03*
X397629Y170500D03*
X397729Y165000D03*
X397629Y177000D03*
Y183500D03*
Y190000D03*
X412329Y214680D03*
X406255Y338850D03*
X407155Y372000D03*
X424929Y205200D03*
X424869Y208670D03*
X419939Y214650D03*
X421755Y372500D03*
X423478Y824500D03*
X423378Y864000D03*
X435029Y151710D03*
X434079Y158620D03*
X434129Y170860D03*
X434219Y164850D03*
X434129Y177400D03*
X434329Y183800D03*
X434449Y202480D03*
X434129Y189750D03*
X434629Y196000D03*
X434439Y208870D03*
X456255Y326500D03*
X1006700Y70500D03*
X1060200Y120500D03*
X1166700Y685500D03*
X1166668Y695284D03*
Y689284D03*
Y700284D03*
X1159700Y704500D03*
X1176200Y701300D03*
X1354700Y456000D03*
G54D28*
X314753Y235852D03*
X307153D03*
X314753Y227852D03*
X307153D03*
X389629Y181700D03*
X382029D03*
X389600Y206929D03*
X382000D03*
X394355Y441000D03*
X386755D03*
X458355Y314600D03*
X471887Y302717D03*
X464287D03*
X465955Y314600D03*
X472455D03*
X480055D03*
X486478Y875500D03*
X494078D03*
X486478Y867500D03*
X494078D03*
X506629Y141000D03*
X499055Y337700D03*
X506655D03*
X499755Y385500D03*
X507355D03*
X499755Y400500D03*
X507355D03*
X514229Y141000D03*
X656162Y465964D03*
X663762D03*
X688300Y446000D03*
X680700D03*
X718948Y107500D03*
X726548D03*
X1050200Y140500D03*
X1057800D03*
X1275300Y433000D03*
X1267700D03*
G54D37*
X376000Y10700D03*
X381000D03*
X625500Y348200D03*
X640500D03*
X635500D03*
X630500D03*
X787000Y400700D03*
X1151000Y702200D03*
G54D46*
X641625Y458750D03*
X654875Y434750D03*
X647125D03*
X651000Y442250D03*
X645500Y466250D03*
X649375Y458750D03*
G54D29*
X307953Y250652D03*
Y243052D03*
X326000Y67700D03*
Y75300D03*
X368500Y17300D03*
Y9700D03*
X391929Y156200D03*
Y163800D03*
X396500Y329300D03*
Y321700D03*
X401429Y197200D03*
Y204800D03*
X418929Y197200D03*
Y204800D03*
X480023Y420983D03*
Y428583D03*
X490429Y135300D03*
Y127700D03*
X498429Y135300D03*
Y127700D03*
X647000Y347700D03*
Y355300D03*
X739748Y137300D03*
Y129700D03*
X1211000Y705200D03*
Y712800D03*
X1227177Y198200D03*
Y205800D03*
G54D38*
X376000Y16300D03*
X381000D03*
X625500Y353800D03*
X640500D03*
X635500D03*
X630500D03*
X787000Y406300D03*
X1151000Y707800D03*
G54D47*
X670800Y446000D03*
X712548Y117000D03*
X1073300Y140500D03*
X1144768Y695784D03*
X1144800Y700500D03*
X1199250Y698520D03*
X1290300Y433000D03*
X1345300Y394500D03*
X1336317Y533012D03*
Y525012D03*
X1341817Y533012D03*
Y525012D03*
G54D48*
X665200Y446000D03*
X706948Y117000D03*
X1067700Y140500D03*
X1139168Y695784D03*
X1139200Y700500D03*
X1193650Y698520D03*
X1284700Y433000D03*
X1330717Y533012D03*
Y525012D03*
X1339700Y394500D03*
X1336217Y533012D03*
Y525012D03*
G54D39*
X367540Y125600D03*
Y123400D03*
X370040Y125600D03*
Y123400D03*
X373540Y125600D03*
Y123400D03*
X376040Y125600D03*
Y123400D03*
X379540Y125600D03*
Y123400D03*
X382040Y125600D03*
Y123400D03*
X385540Y125600D03*
Y123400D03*
X388040Y125600D03*
Y123400D03*
X391540Y125600D03*
Y123400D03*
X394040Y125600D03*
Y123400D03*
X397540Y125667D03*
Y123467D03*
X400040Y125667D03*
Y123467D03*
X403540Y125600D03*
Y123400D03*
X406040Y125600D03*
Y123400D03*
X409540Y125600D03*
Y123400D03*
X412040Y125600D03*
Y123400D03*
X403055Y326100D03*
Y323900D03*
X444255Y394600D03*
Y392400D03*
X436355Y394200D03*
Y392000D03*
X450455Y364800D03*
Y362600D03*
X453855Y381100D03*
Y378900D03*
Y388400D03*
Y386200D03*
X451355Y395000D03*
Y392800D03*
X463535Y354910D03*
Y352710D03*
X482000Y133100D03*
Y130900D03*
X484929Y133100D03*
Y130900D03*
X482055Y375100D03*
Y372900D03*
X488555Y388100D03*
Y385900D03*
X489055Y396100D03*
Y393900D03*
X488555Y412100D03*
Y409900D03*
G54D49*
X673200Y466000D03*
X1341717Y533012D03*
Y525012D03*
M02*
